FILE_TYPE = MACRO_DRAWING;
SET COLOR_WIRE YELLOW;
SET COLOR_PROP MONO;
SET COLOR_DOT WHITE;
SET COLOR_ARC YELLOW;
SET COLOR_BODY GREEN;
SET COLOR_NOTE MONO;
SET PROP_DISPLAY VALUE;
SET PAGE_NUMBER P121;
FORCEADD OFFPAGE..1
(-6600 3350);
FORCEPROP 2 LAST $XR1 121 
J 0
(-6972 3350);
DISPLAY 0.638298 (-6972 3350);
PAINT MONO (-6972 3350);
FORCEPROP 2 LAST $XR0 101 
J 0
(-6852 3350);
DISPLAY 0.638298 (-6852 3350);
PAINT MONO (-6852 3350);
FORCEPROP 2 LAST PATH I10
J 0
(-6550 3425);
DISPLAY 1.021277 (-6550 3425);
PAINT ORANGE (-6550 3425);
DISPLAY INVISIBLE (-6550 3425);
FORCEPROP 1 LAST COMMENT_BODY TRUE
J 0
(-6475 3250);
DISPLAY 1.404255 (-6475 3250);
PAINT PEACH (-6475 3250);
DISPLAY INVISIBLE (-6475 3250);
FORCEPROP 1 LAST OFFPAGE TRUE
J 0
(-6275 3225);
PAINT GREEN (-6275 3225);
DISPLAY INVISIBLE (-6275 3225);
FORCEPROP 2 LAST CDS_LIB mstr_standard
J 0
(-6600 3350);
PAINT ORANGE (-6600 3350);
DISPLAY INVISIBLE (-6600 3350);
FORCEADD OFFPAGE..5
(-6050 1175);
FORCEPROP 2 LAST $XR1 139 
J 0
(-6455 1175);
DISPLAY 0.638298 (-6455 1175);
PAINT MONO (-6455 1175);
FORCEPROP 2 LAST $XR0 125 
J 0
(-6335 1175);
DISPLAY 0.638298 (-6335 1175);
PAINT MONO (-6335 1175);
FORCEPROP 1 LAST COMMENT_BODY TRUE
J 0
(-5950 1100);
DISPLAY 0.872340 (-5950 1100);
PAINT GREEN (-5950 1100);
DISPLAY INVISIBLE (-5950 1100);
FORCEPROP 1 LAST OFFPAGE TRUE
J 0
(-5725 1050);
DISPLAY 0.872340 (-5725 1050);
PAINT GREEN (-5725 1050);
DISPLAY INVISIBLE (-5725 1050);
FORCEPROP 2 LAST CDS_LIB mstr_standard
J 0
(-6050 1175);
PAINT ORANGE (-6050 1175);
DISPLAY INVISIBLE (-6050 1175);
FORCEPROP 2 LAST PATH I100
J 0
(-6325 1225);
DISPLAY 1.021277 (-6325 1225);
PAINT ORANGE (-6325 1225);
DISPLAY INVISIBLE (-6325 1225);
FORCEADD RES..1
(-5100 1175);
FORCEPROP 1 LASTPIN (-5000 1175) $PN 2
J 0
(-5038 1187);
DISPLAY 0.617021 (-5038 1187);
PAINT ORANGE (-5038 1187);
FORCEPROP 1 LAST TOLERANCE 1%
J 0
(-5125 1125);
DISPLAY 0.617021 (-5125 1125);
PAINT SKYBLUE (-5125 1125);
FORCEPROP 1 LAST VALUE 33.2
J 2
(-5200 1175);
DISPLAY 0.617021 (-5200 1175);
PAINT SKYBLUE (-5200 1175);
FORCEPROP 1 LASTPIN (-5200 1175) $PN 1
J 0
(-5188 1187);
DISPLAY 0.617021 (-5188 1187);
PAINT ORANGE (-5188 1187);
FORCEPROP 1 LAST LOCATION R8D11
J 0
(-5150 1225);
DISPLAY 0.617021 (-5150 1225);
PAINT AQUA (-5150 1225);
FORCEPROP 1 LAST PART_NUMBER G21796-074
J 0
(-5350 1125);
DISPLAY 0.617021 (-5350 1125);
PAINT BLUE (-5350 1125);
FORCEPROP 1 LAST WATTAGE 1/16W
J 2
(-4625 1125);
DISPLAY 0.617021 (-4625 1125);
PAINT SKYBLUE (-4625 1125);
FORCEPROP 1 LAST PACK_TYPE 0402
J 0
(-4900 1125);
DISPLAY 0.617021 (-4900 1125);
PAINT SKYBLUE (-4900 1125);
FORCEPROP 1 LAST MATERIAL CHIP
J 0
(-5025 1125);
DISPLAY 0.617021 (-5025 1125);
PAINT SKYBLUE (-5025 1125);
FORCEPROP 1 LAST PATH I101
J 0
(-5150 1325);
DISPLAY 0.978723 (-5150 1325);
PAINT WHITE (-5150 1325);
DISPLAY INVISIBLE (-5150 1325);
FORCEPROP 0 LAST CDS_SEC 1
J 0
(-5200 1275);
PAINT ORANGE (-5200 1275);
DISPLAY INVISIBLE (-5200 1275);
FORCEPROP 2 LAST CDS_LOCATION R8D11
J 0
(-4900 1125);
DISPLAY 0.617021 (-4900 1125);
PAINT AQUA (-4900 1125);
DISPLAY INVISIBLE (-4900 1125);
FORCEPROP 2 LAST SEC 1
J 0
(-5150 1375);
DISPLAY 0.680851 (-5150 1375);
PAINT MONO (-5150 1375);
DISPLAY INVISIBLE (-5150 1375);
FORCEPROP 2 LAST SEC_TYPE 0402
J 0
(-5150 1375);
DISPLAY 1.021277 (-5150 1375);
PAINT ORANGE (-5150 1375);
DISPLAY INVISIBLE (-5150 1375);
FORCEPROP 2 LAST CDS_LIB mstr_discrete
J 0
(-5100 1175);
PAINT ORANGE (-5100 1175);
DISPLAY INVISIBLE (-5100 1175);
FORCEPROP 0 LAST ROOM SB
J 0
(-5050 1275);
DISPLAY 1.021277 (-5050 1275);
PAINT ORANGE (-5050 1275);
DISPLAY INVISIBLE (-5050 1275);
FORCEADD OFFPAGE..5
(-6600 3700);
FORCEPROP 2 LAST $XR0 121 
J 0
(-6855 3700);
DISPLAY 0.638298 (-6855 3700);
PAINT MONO (-6855 3700);
FORCEPROP 2 LAST CDS_LIB mstr_standard
J 0
(-6600 3700);
PAINT ORANGE (-6600 3700);
DISPLAY INVISIBLE (-6600 3700);
FORCEPROP 2 LAST PATH I102
J 0
(-6550 3775);
DISPLAY 1.021277 (-6550 3775);
PAINT ORANGE (-6550 3775);
DISPLAY INVISIBLE (-6550 3775);
FORCEPROP 1 LAST OFFPAGE TRUE
J 0
(-6275 3575);
DISPLAY 0.872340 (-6275 3575);
PAINT GREEN (-6275 3575);
DISPLAY INVISIBLE (-6275 3575);
FORCEPROP 1 LAST COMMENT_BODY TRUE
J 0
(-6500 3625);
DISPLAY 0.872340 (-6500 3625);
PAINT GREEN (-6500 3625);
DISPLAY INVISIBLE (-6500 3625);
FORCEADD OFFPAGE..5
(-6600 3650);
FORCEPROP 2 LAST $XR0 121 
J 0
(-6855 3650);
DISPLAY 0.638298 (-6855 3650);
PAINT MONO (-6855 3650);
FORCEPROP 2 LAST CDS_LIB mstr_standard
J 0
(-6600 3650);
PAINT ORANGE (-6600 3650);
DISPLAY INVISIBLE (-6600 3650);
FORCEPROP 2 LAST PATH I103
J 0
(-6550 3725);
DISPLAY 1.021277 (-6550 3725);
PAINT ORANGE (-6550 3725);
DISPLAY INVISIBLE (-6550 3725);
FORCEPROP 1 LAST OFFPAGE TRUE
J 0
(-6275 3525);
DISPLAY 0.872340 (-6275 3525);
PAINT GREEN (-6275 3525);
DISPLAY INVISIBLE (-6275 3525);
FORCEPROP 1 LAST COMMENT_BODY TRUE
J 0
(-6500 3575);
DISPLAY 0.872340 (-6500 3575);
PAINT GREEN (-6500 3575);
DISPLAY INVISIBLE (-6500 3575);
FORCEADD OFFPAGE..5
(-6600 3600);
FORCEPROP 2 LAST $XR0 121 
J 0
(-6855 3600);
DISPLAY 0.638298 (-6855 3600);
PAINT MONO (-6855 3600);
FORCEPROP 2 LAST CDS_LIB mstr_standard
J 0
(-6600 3600);
PAINT ORANGE (-6600 3600);
DISPLAY INVISIBLE (-6600 3600);
FORCEPROP 2 LAST PATH I104
J 0
(-6550 3675);
DISPLAY 1.021277 (-6550 3675);
PAINT ORANGE (-6550 3675);
DISPLAY INVISIBLE (-6550 3675);
FORCEPROP 1 LAST OFFPAGE TRUE
J 0
(-6275 3475);
DISPLAY 0.872340 (-6275 3475);
PAINT GREEN (-6275 3475);
DISPLAY INVISIBLE (-6275 3475);
FORCEPROP 1 LAST COMMENT_BODY TRUE
J 0
(-6500 3525);
DISPLAY 0.872340 (-6500 3525);
PAINT GREEN (-6500 3525);
DISPLAY INVISIBLE (-6500 3525);
FORCEADD OFFPAGE..5
(-6600 3550);
FORCEPROP 2 LAST $XR0 121 
J 0
(-6855 3550);
DISPLAY 0.638298 (-6855 3550);
PAINT MONO (-6855 3550);
FORCEPROP 2 LAST CDS_LIB mstr_standard
J 0
(-6600 3550);
PAINT ORANGE (-6600 3550);
DISPLAY INVISIBLE (-6600 3550);
FORCEPROP 2 LAST PATH I105
J 0
(-6550 3625);
DISPLAY 1.021277 (-6550 3625);
PAINT ORANGE (-6550 3625);
DISPLAY INVISIBLE (-6550 3625);
FORCEPROP 1 LAST OFFPAGE TRUE
J 0
(-6275 3425);
DISPLAY 0.872340 (-6275 3425);
PAINT GREEN (-6275 3425);
DISPLAY INVISIBLE (-6275 3425);
FORCEPROP 1 LAST COMMENT_BODY TRUE
J 0
(-6500 3475);
DISPLAY 0.872340 (-6500 3475);
PAINT GREEN (-6500 3475);
DISPLAY INVISIBLE (-6500 3475);
FORCEADD OFFPAGE..5
(-6600 3800);
FORCEPROP 2 LAST $XR0 121 
J 0
(-6855 3800);
DISPLAY 0.638298 (-6855 3800);
PAINT MONO (-6855 3800);
FORCEPROP 2 LAST CDS_LIB mstr_standard
J 0
(-6600 3800);
PAINT ORANGE (-6600 3800);
DISPLAY INVISIBLE (-6600 3800);
FORCEPROP 2 LAST PATH I106
J 0
(-6550 3875);
DISPLAY 1.021277 (-6550 3875);
PAINT ORANGE (-6550 3875);
DISPLAY INVISIBLE (-6550 3875);
FORCEPROP 1 LAST OFFPAGE TRUE
J 0
(-6275 3675);
DISPLAY 0.872340 (-6275 3675);
PAINT GREEN (-6275 3675);
DISPLAY INVISIBLE (-6275 3675);
FORCEPROP 1 LAST COMMENT_BODY TRUE
J 0
(-6500 3725);
DISPLAY 0.872340 (-6500 3725);
PAINT GREEN (-6500 3725);
DISPLAY INVISIBLE (-6500 3725);
FORCEADD OFFPAGE..4
(-4125 1175);
FORCEPROP 2 LAST $XR0 121 
J 0
(-3939 1175);
DISPLAY 0.638298 (-3939 1175);
PAINT MONO (-3939 1175);
FORCEPROP 1 LAST COMMENT_BODY TRUE
J 0
(-4150 1075);
DISPLAY 0.872340 (-4150 1075);
PAINT GREEN (-4150 1075);
DISPLAY INVISIBLE (-4150 1075);
FORCEPROP 1 LAST OFFPAGE TRUE
J 0
(-3800 1050);
DISPLAY 0.872340 (-3800 1050);
PAINT GREEN (-3800 1050);
DISPLAY INVISIBLE (-3800 1050);
FORCEPROP 2 LAST PATH I107
J 0
(-3950 1250);
DISPLAY 1.021277 (-3950 1250);
PAINT ORANGE (-3950 1250);
DISPLAY INVISIBLE (-3950 1250);
FORCEPROP 2 LAST CDS_LIB mstr_standard
J 0
(-4125 1175);
PAINT ORANGE (-4125 1175);
DISPLAY INVISIBLE (-4125 1175);
FORCEADD OFFPAGE..4
(-4125 1025);
FORCEPROP 2 LAST $XR0 121 
J 0
(-3939 1025);
DISPLAY 0.638298 (-3939 1025);
PAINT MONO (-3939 1025);
FORCEPROP 2 LAST CDS_LIB mstr_standard
J 0
(-4125 1025);
PAINT ORANGE (-4125 1025);
DISPLAY INVISIBLE (-4125 1025);
FORCEPROP 2 LAST PATH I108
J 0
(-3950 1100);
DISPLAY 1.021277 (-3950 1100);
PAINT ORANGE (-3950 1100);
DISPLAY INVISIBLE (-3950 1100);
FORCEPROP 1 LAST OFFPAGE TRUE
J 0
(-3800 900);
DISPLAY 0.872340 (-3800 900);
PAINT GREEN (-3800 900);
DISPLAY INVISIBLE (-3800 900);
FORCEPROP 1 LAST COMMENT_BODY TRUE
J 0
(-4150 925);
DISPLAY 0.872340 (-4150 925);
PAINT GREEN (-4150 925);
DISPLAY INVISIBLE (-4150 925);
FORCEADD OFFPAGE..4
(-4125 850);
FORCEPROP 2 LAST $XR0 121 
J 0
(-3939 850);
DISPLAY 0.638298 (-3939 850);
PAINT MONO (-3939 850);
FORCEPROP 2 LAST CDS_LIB mstr_standard
J 0
(-4125 850);
PAINT ORANGE (-4125 850);
DISPLAY INVISIBLE (-4125 850);
FORCEPROP 2 LAST PATH I109
J 0
(-3950 925);
DISPLAY 1.021277 (-3950 925);
PAINT ORANGE (-3950 925);
DISPLAY INVISIBLE (-3950 925);
FORCEPROP 1 LAST OFFPAGE TRUE
J 0
(-3800 725);
DISPLAY 0.872340 (-3800 725);
PAINT GREEN (-3800 725);
DISPLAY INVISIBLE (-3800 725);
FORCEPROP 1 LAST COMMENT_BODY TRUE
J 0
(-4150 750);
DISPLAY 0.872340 (-4150 750);
PAINT GREEN (-4150 750);
DISPLAY INVISIBLE (-4150 750);
FORCEADD OFFPAGE..1
(-6600 3850);
FORCEPROP 2 LAST $XR0 190 
J 0
(-6852 3850);
DISPLAY 0.638298 (-6852 3850);
PAINT MONO (-6852 3850);
FORCEPROP 2 LAST CDS_LIB mstr_standard
J 0
(-6600 3850);
PAINT ORANGE (-6600 3850);
DISPLAY INVISIBLE (-6600 3850);
FORCEPROP 1 LAST OFFPAGE TRUE
J 0
(-6275 3725);
PAINT GREEN (-6275 3725);
DISPLAY INVISIBLE (-6275 3725);
FORCEPROP 1 LAST COMMENT_BODY TRUE
J 0
(-6475 3750);
DISPLAY 1.404255 (-6475 3750);
PAINT PEACH (-6475 3750);
DISPLAY INVISIBLE (-6475 3750);
FORCEPROP 2 LAST PATH I11
J 0
(-6550 3925);
DISPLAY 1.021277 (-6550 3925);
PAINT ORANGE (-6550 3925);
DISPLAY INVISIBLE (-6550 3925);
FORCEADD OFFPAGE..4
(-4125 700);
FORCEPROP 2 LAST $XR0 121 
J 0
(-3939 700);
DISPLAY 0.638298 (-3939 700);
PAINT MONO (-3939 700);
FORCEPROP 2 LAST CDS_LIB mstr_standard
J 0
(-4125 700);
PAINT ORANGE (-4125 700);
DISPLAY INVISIBLE (-4125 700);
FORCEPROP 2 LAST PATH I110
J 0
(-3950 775);
DISPLAY 1.021277 (-3950 775);
PAINT ORANGE (-3950 775);
DISPLAY INVISIBLE (-3950 775);
FORCEPROP 1 LAST OFFPAGE TRUE
J 0
(-3800 575);
DISPLAY 0.872340 (-3800 575);
PAINT GREEN (-3800 575);
DISPLAY INVISIBLE (-3800 575);
FORCEPROP 1 LAST COMMENT_BODY TRUE
J 0
(-4150 600);
DISPLAY 0.872340 (-4150 600);
PAINT GREEN (-4150 600);
DISPLAY INVISIBLE (-4150 600);
FORCEADD OFFPAGE..4
(-4125 550);
FORCEPROP 2 LAST $XR0 121 
J 0
(-3939 550);
DISPLAY 0.638298 (-3939 550);
PAINT MONO (-3939 550);
FORCEPROP 2 LAST CDS_LIB mstr_standard
J 0
(-4125 550);
PAINT ORANGE (-4125 550);
DISPLAY INVISIBLE (-4125 550);
FORCEPROP 2 LAST PATH I111
J 0
(-3950 625);
DISPLAY 1.021277 (-3950 625);
PAINT ORANGE (-3950 625);
DISPLAY INVISIBLE (-3950 625);
FORCEPROP 1 LAST OFFPAGE TRUE
J 0
(-3800 425);
DISPLAY 0.872340 (-3800 425);
PAINT GREEN (-3800 425);
DISPLAY INVISIBLE (-3800 425);
FORCEPROP 1 LAST COMMENT_BODY TRUE
J 0
(-4150 450);
DISPLAY 0.872340 (-4150 450);
PAINT GREEN (-4150 450);
DISPLAY INVISIBLE (-4150 450);
FORCEADD OFFPAGE..1
(-6600 2400);
FORCEPROP 2 LAST $XR0 133 
J 0
(-6852 2400);
DISPLAY 0.638298 (-6852 2400);
PAINT MONO (-6852 2400);
FORCEPROP 1 LAST COMMENT_BODY TRUE
J 0
(-6475 2300);
DISPLAY 0.872340 (-6475 2300);
PAINT GREEN (-6475 2300);
DISPLAY INVISIBLE (-6475 2300);
FORCEPROP 1 LAST OFFPAGE TRUE
J 0
(-6275 2275);
DISPLAY 0.872340 (-6275 2275);
PAINT GREEN (-6275 2275);
DISPLAY INVISIBLE (-6275 2275);
FORCEPROP 2 LAST PATH I112
J 0
(-6550 2475);
DISPLAY 1.021277 (-6550 2475);
PAINT ORANGE (-6550 2475);
DISPLAY INVISIBLE (-6550 2475);
FORCEPROP 2 LAST CDS_LIB mstr_standard
J 0
(-6600 2400);
PAINT MONO (-6600 2400);
DISPLAY INVISIBLE (-6600 2400);
FORCEADD OFFPAGE..1
(-6600 3750);
FORCEPROP 2 LAST $XR0 139 
J 0
(-6852 3750);
DISPLAY 0.638298 (-6852 3750);
PAINT MONO (-6852 3750);
FORCEPROP 2 LAST CDS_LIB mstr_standard
J 0
(-6600 3750);
PAINT ORANGE (-6600 3750);
DISPLAY INVISIBLE (-6600 3750);
FORCEPROP 1 LAST OFFPAGE TRUE
J 0
(-6275 3625);
PAINT GREEN (-6275 3625);
DISPLAY INVISIBLE (-6275 3625);
FORCEPROP 1 LAST COMMENT_BODY TRUE
J 0
(-6475 3650);
DISPLAY 1.404255 (-6475 3650);
PAINT PEACH (-6475 3650);
DISPLAY INVISIBLE (-6475 3650);
FORCEPROP 2 LAST PATH I21
J 0
(-6550 3825);
DISPLAY 1.021277 (-6550 3825);
PAINT ORANGE (-6550 3825);
DISPLAY INVISIBLE (-6550 3825);
FORCEADD OFFPAGE..4
(-1375 2550);
FORCEPROP 2 LASTPIN (-1425 2550) SIG_NAME RST_RTCRST_N
J 2
(-1435 2560);
DISPLAY 0.617021 (-1435 2560);
PAINT ORANGE (-1435 2560);
FORCEPROP 2 LAST $XR0 137 
J 0
(-1189 2550);
DISPLAY 0.638298 (-1189 2550);
PAINT MONO (-1189 2550);
FORCEPROP 2 LAST PATH I24
J 0
(-1200 2625);
DISPLAY 1.021277 (-1200 2625);
PAINT ORANGE (-1200 2625);
DISPLAY INVISIBLE (-1200 2625);
FORCEPROP 1 LAST COMMENT_BODY TRUE
J 0
(-1400 2450);
DISPLAY 0.872340 (-1400 2450);
PAINT GREEN (-1400 2450);
DISPLAY INVISIBLE (-1400 2450);
FORCEPROP 1 LAST OFFPAGE TRUE
J 0
(-1050 2425);
DISPLAY 0.872340 (-1050 2425);
PAINT GREEN (-1050 2425);
DISPLAY INVISIBLE (-1050 2425);
FORCEPROP 2 LAST CDS_LIB mstr_standard
J 0
(-1375 2550);
PAINT ORANGE (-1375 2550);
DISPLAY INVISIBLE (-1375 2550);
FORCEADD OFFPAGE..4
(-1375 2500);
FORCEPROP 2 LASTPIN (-1425 2500) SIG_NAME RST_SRTCRST_N
J 2
(-1435 2510);
DISPLAY 0.617021 (-1435 2510);
PAINT ORANGE (-1435 2510);
FORCEPROP 2 LAST $XR0 137 
J 0
(-1189 2500);
DISPLAY 0.638298 (-1189 2500);
PAINT MONO (-1189 2500);
FORCEPROP 2 LAST PATH I25
J 0
(-1200 2575);
DISPLAY 1.021277 (-1200 2575);
PAINT ORANGE (-1200 2575);
DISPLAY INVISIBLE (-1200 2575);
FORCEPROP 1 LAST COMMENT_BODY TRUE
J 0
(-1400 2400);
DISPLAY 0.872340 (-1400 2400);
PAINT GREEN (-1400 2400);
DISPLAY INVISIBLE (-1400 2400);
FORCEPROP 1 LAST OFFPAGE TRUE
J 0
(-1050 2375);
DISPLAY 0.872340 (-1050 2375);
PAINT GREEN (-1050 2375);
DISPLAY INVISIBLE (-1050 2375);
FORCEPROP 2 LAST CDS_LIB mstr_standard
J 0
(-1375 2500);
PAINT ORANGE (-1375 2500);
DISPLAY INVISIBLE (-1375 2500);
FORCEADD OFFPAGE..2
(-1375 3700);
FORCEPROP 2 LASTPIN (-1425 3700) SIG_NAME FM_PCH_PRSNT_N
J 2
(-1435 3710);
DISPLAY 0.617021 (-1435 3710);
PAINT ORANGE (-1435 3710);
FORCEPROP 2 LAST $XR1 191 
J 0
(-1066 3700);
DISPLAY 0.638298 (-1066 3700);
PAINT MONO (-1066 3700);
FORCEPROP 2 LAST $XR0 133 
J 0
(-1186 3700);
DISPLAY 0.638298 (-1186 3700);
PAINT MONO (-1186 3700);
FORCEPROP 2 LAST PATH I27
J 0
(-1200 3775);
DISPLAY 1.021277 (-1200 3775);
PAINT ORANGE (-1200 3775);
DISPLAY INVISIBLE (-1200 3775);
FORCEPROP 1 LAST COMMENT_BODY TRUE
J 0
(-1420 3605);
DISPLAY 0.872340 (-1420 3605);
PAINT GREEN (-1420 3605);
DISPLAY INVISIBLE (-1420 3605);
FORCEPROP 1 LAST OFFPAGE TRUE
J 0
(-1050 3575);
DISPLAY 0.872340 (-1050 3575);
PAINT GREEN (-1050 3575);
DISPLAY INVISIBLE (-1050 3575);
FORCEPROP 2 LAST CDS_LIB mstr_standard
J 0
(-1375 3700);
PAINT ORANGE (-1375 3700);
DISPLAY INVISIBLE (-1375 3700);
FORCEADD OFFPAGE..2
(-1375 3450);
FORCEPROP 2 LAST $XR1 184 
J 0
(-1066 3450);
DISPLAY 0.638298 (-1066 3450);
PAINT MONO (-1066 3450);
FORCEPROP 2 LAST $XR0 154 
J 0
(-1186 3450);
DISPLAY 0.638298 (-1186 3450);
PAINT MONO (-1186 3450);
FORCEPROP 2 LAST PATH I28
J 0
(-1175 3500);
DISPLAY 1.021277 (-1175 3500);
PAINT ORANGE (-1175 3500);
DISPLAY INVISIBLE (-1175 3500);
FORCEPROP 1 LAST COMMENT_BODY TRUE
J 0
(-1420 3355);
DISPLAY 1.404255 (-1420 3355);
PAINT GREEN (-1420 3355);
DISPLAY INVISIBLE (-1420 3355);
FORCEPROP 1 LAST OFFPAGE TRUE
J 0
(-1050 3325);
PAINT GREEN (-1050 3325);
DISPLAY INVISIBLE (-1050 3325);
FORCEPROP 2 LAST CDS_LIB mstr_standard
J 0
(-1375 3450);
PAINT RED (-1375 3450);
DISPLAY INVISIBLE (-1375 3450);
FORCEADD OFFPAGE..2
(-1375 3150);
FORCEPROP 2 LAST $XR3 184 
J 0
(-826 3150);
DISPLAY 0.638298 (-826 3150);
PAINT MONO (-826 3150);
FORCEPROP 2 LAST $XR2 154 
J 0
(-946 3150);
DISPLAY 0.638298 (-946 3150);
PAINT MONO (-946 3150);
FORCEPROP 2 LAST $XR1 125 
J 0
(-1066 3150);
DISPLAY 0.638298 (-1066 3150);
PAINT MONO (-1066 3150);
FORCEPROP 2 LAST $XR0 111 
J 0
(-1186 3150);
DISPLAY 0.638298 (-1186 3150);
PAINT MONO (-1186 3150);
FORCEPROP 2 LAST PATH I29
J 0
(-1175 3200);
DISPLAY 1.021277 (-1175 3200);
PAINT ORANGE (-1175 3200);
DISPLAY INVISIBLE (-1175 3200);
FORCEPROP 1 LAST COMMENT_BODY TRUE
J 0
(-1420 3055);
DISPLAY 1.404255 (-1420 3055);
PAINT GREEN (-1420 3055);
DISPLAY INVISIBLE (-1420 3055);
FORCEPROP 1 LAST OFFPAGE TRUE
J 0
(-1050 3025);
PAINT GREEN (-1050 3025);
DISPLAY INVISIBLE (-1050 3025);
FORCEPROP 2 LAST CDS_LIB mstr_standard
J 0
(-1375 3150);
PAINT RED (-1375 3150);
DISPLAY INVISIBLE (-1375 3150);
FORCEADD RES..1
(-1925 3150);
FORCEPROP 1 LASTPIN (-2025 3150) $PN 1
J 0
(-2013 3162);
DISPLAY 0.617021 (-2013 3162);
PAINT MONO (-2013 3162);
FORCEPROP 1 LASTPIN (-1825 3150) $PN 2
J 0
(-1863 3162);
DISPLAY 0.617021 (-1863 3162);
PAINT MONO (-1863 3162);
FORCEPROP 1 LAST WATTAGE 1/16W
J 2
(-2050 3100);
DISPLAY 0.617021 (-2050 3100);
PAINT SKYBLUE (-2050 3100);
FORCEPROP 1 LAST MATERIAL CHIP
J 0
(-1800 3100);
DISPLAY 0.617021 (-1800 3100);
PAINT SKYBLUE (-1800 3100);
FORCEPROP 1 LAST PACK_TYPE 0402
J 0
(-1700 3100);
DISPLAY 0.617021 (-1700 3100);
PAINT SKYBLUE (-1700 3100);
FORCEPROP 1 LAST TOLERANCE 5%
J 0
(-1875 3100);
DISPLAY 0.617021 (-1875 3100);
PAINT SKYBLUE (-1875 3100);
FORCEPROP 1 LAST LOCATION R7C15
J 0
(-2125 3150);
DISPLAY 0.617021 (-2125 3150);
PAINT AQUA (-2125 3150);
FORCEPROP 1 LAST PART_NUMBER G21497-005
J 0
(-2375 3100);
DISPLAY 0.617021 (-2375 3100);
PAINT BLUE (-2375 3100);
FORCEPROP 1 LAST VALUE 0.0
J 2
(-1950 3100);
DISPLAY 0.617021 (-1950 3100);
PAINT SKYBLUE (-1950 3100);
FORCEPROP 2 LAST CDS_LOCATION R7C15
J 0
(-2125 3150);
DISPLAY 0.617021 (-2125 3150);
PAINT AQUA (-2125 3150);
DISPLAY INVISIBLE (-2125 3150);
FORCEPROP 2 LAST $SEC 1
J 0
(-1975 3350);
DISPLAY 0.936170 (-1975 3350);
PAINT MONO (-1975 3350);
DISPLAY INVISIBLE (-1975 3350);
FORCEPROP 2 LAST CDS_SEC 1
J 0
(-1975 3350);
DISPLAY 1.404255 (-1975 3350);
PAINT ORANGE (-1975 3350);
DISPLAY INVISIBLE (-1975 3350);
FORCEPROP 2 LAST CDS_LIB mstr_discrete
J 0
(-1925 3150);
PAINT RED (-1925 3150);
DISPLAY INVISIBLE (-1925 3150);
FORCEPROP 1 LAST PATH I31
J 0
(-1975 3300);
DISPLAY 0.978723 (-1975 3300);
PAINT WHITE (-1975 3300);
DISPLAY INVISIBLE (-1975 3300);
FORCEPROP 2 LAST ROOM SB
J 0
(-1975 3290);
DISPLAY 0.787234 (-1975 3290);
PAINT SKYBLUE (-1975 3290);
DISPLAY INVISIBLE (-1975 3290);
FORCEADD OFFPAGE..2
(-1375 3550);
FORCEPROP 2 LAST $XR0 154 
J 0
(-1186 3550);
DISPLAY 0.638298 (-1186 3550);
PAINT MONO (-1186 3550);
FORCEPROP 2 LAST PATH I32
J 0
(-1175 3600);
DISPLAY 1.021277 (-1175 3600);
PAINT ORANGE (-1175 3600);
DISPLAY INVISIBLE (-1175 3600);
FORCEPROP 1 LAST COMMENT_BODY TRUE
J 0
(-1420 3455);
DISPLAY 1.404255 (-1420 3455);
PAINT GREEN (-1420 3455);
DISPLAY INVISIBLE (-1420 3455);
FORCEPROP 1 LAST OFFPAGE TRUE
J 0
(-1050 3425);
PAINT GREEN (-1050 3425);
DISPLAY INVISIBLE (-1050 3425);
FORCEPROP 2 LAST CDS_LIB mstr_standard
J 0
(-1375 3550);
PAINT RED (-1375 3550);
DISPLAY INVISIBLE (-1375 3550);
FORCEADD RES..1
(-1950 3550);
FORCEPROP 1 LAST PACK_TYPE 0402
J 0
(-1725 3500);
DISPLAY 0.617021 (-1725 3500);
PAINT SKYBLUE (-1725 3500);
FORCEPROP 1 LASTPIN (-2050 3550) $PN 1
J 0
(-2038 3562);
DISPLAY 0.617021 (-2038 3562);
PAINT MONO (-2038 3562);
FORCEPROP 1 LASTPIN (-1850 3550) $PN 2
J 0
(-1888 3562);
DISPLAY 0.617021 (-1888 3562);
PAINT MONO (-1888 3562);
FORCEPROP 1 LAST MATERIAL CHIP
J 0
(-1825 3500);
DISPLAY 0.617021 (-1825 3500);
PAINT SKYBLUE (-1825 3500);
FORCEPROP 1 LAST TOLERANCE 1%
J 0
(-1900 3500);
DISPLAY 0.617021 (-1900 3500);
PAINT SKYBLUE (-1900 3500);
FORCEPROP 1 LAST LOCATION R7C16
J 0
(-2000 3600);
DISPLAY 0.617021 (-2000 3600);
PAINT AQUA (-2000 3600);
FORCEPROP 1 LAST PART_NUMBER G21796-074
J 0
(-2400 3500);
DISPLAY 0.617021 (-2400 3500);
PAINT BLUE (-2400 3500);
FORCEPROP 1 LAST WATTAGE 1/16W
J 2
(-2075 3500);
DISPLAY 0.617021 (-2075 3500);
PAINT SKYBLUE (-2075 3500);
FORCEPROP 1 LAST VALUE 33.2
J 2
(-1975 3500);
DISPLAY 0.617021 (-1975 3500);
PAINT SKYBLUE (-1975 3500);
FORCEPROP 2 LAST CDS_LOCATION R7C16
J 0
(-2000 3600);
DISPLAY 0.617021 (-2000 3600);
PAINT AQUA (-2000 3600);
DISPLAY INVISIBLE (-2000 3600);
FORCEPROP 2 LAST $SEC 1
J 0
(-2000 3750);
DISPLAY 0.936170 (-2000 3750);
PAINT MONO (-2000 3750);
DISPLAY INVISIBLE (-2000 3750);
FORCEPROP 2 LAST CDS_SEC 1
J 0
(-2000 3750);
DISPLAY 1.404255 (-2000 3750);
PAINT ORANGE (-2000 3750);
DISPLAY INVISIBLE (-2000 3750);
FORCEPROP 2 LAST CDS_LIB mstr_discrete
J 0
(-1950 3550);
PAINT RED (-1950 3550);
DISPLAY INVISIBLE (-1950 3550);
FORCEPROP 1 LAST PATH I33
J 0
(-2000 3700);
DISPLAY 0.978723 (-2000 3700);
PAINT WHITE (-2000 3700);
DISPLAY INVISIBLE (-2000 3700);
FORCEPROP 2 LAST ROOM SB
J 0
(-2000 3690);
DISPLAY 0.787234 (-2000 3690);
PAINT SKYBLUE (-2000 3690);
DISPLAY INVISIBLE (-2000 3690);
FORCEADD LBG_CORE_QAT_EXT_D..8
(-4050 2800);
FORCEPROP 2 LASTPIN (-5400 2150) $PN P44
J 2
(-5410 2160);
DISPLAY 0.617021 (-5410 2160);
PAINT ORANGE (-5410 2160);
FORCEPROP 2 LASTPIN (-5400 2900) $PN Y15
J 2
(-5410 2910);
DISPLAY 0.617021 (-5410 2910);
PAINT ORANGE (-5410 2910);
FORCEPROP 2 LASTPIN (-5400 3200) $PN AE7
J 2
(-5410 3210);
DISPLAY 0.617021 (-5410 3210);
PAINT ORANGE (-5410 3210);
FORCEPROP 2 LASTPIN (-5400 3150) $PN AA9
J 2
(-5410 3160);
DISPLAY 0.617021 (-5410 3160);
PAINT ORANGE (-5410 3160);
FORCEPROP 2 LASTPIN (-5400 2950) $PN AD13
J 2
(-5410 2960);
DISPLAY 0.617021 (-5410 2960);
PAINT ORANGE (-5410 2960);
FORCEPROP 2 LASTPIN (-5400 3650) $PN AN1
J 2
(-5410 3660);
DISPLAY 0.617021 (-5410 3660);
PAINT ORANGE (-5410 3660);
FORCEPROP 2 LASTPIN (-5400 2650) $PN AA17
J 2
(-5410 2660);
DISPLAY 0.617021 (-5410 2660);
PAINT ORANGE (-5410 2660);
FORCEPROP 2 LASTPIN (-5400 3050) $PN Y11
J 2
(-5410 3060);
DISPLAY 0.617021 (-5410 3060);
PAINT ORANGE (-5410 3060);
FORCEPROP 2 LASTPIN (-5400 3450) $PN AK2
J 2
(-5410 3460);
DISPLAY 0.617021 (-5410 3460);
PAINT ORANGE (-5410 3460);
FORCEPROP 2 LASTPIN (-5400 3400) $PN AM2
J 2
(-5410 3410);
DISPLAY 0.617021 (-5410 3410);
PAINT ORANGE (-5410 3410);
FORCEPROP 2 LASTPIN (-5400 3800) $PN AK4
J 2
(-5410 3810);
DISPLAY 0.617021 (-5410 3810);
PAINT ORANGE (-5410 3810);
FORCEPROP 2 LASTPIN (-5400 3700) $PN AH2
J 2
(-5410 3710);
DISPLAY 0.617021 (-5410 3710);
PAINT ORANGE (-5410 3710);
FORCEPROP 2 LASTPIN (-2700 2500) $PN G18
J 0
(-2690 2510);
DISPLAY 0.617021 (-2690 2510);
PAINT ORANGE (-2690 2510);
FORCEPROP 2 LASTPIN (-2700 3400) $PN K4
J 0
(-2690 3410);
DISPLAY 0.617021 (-2690 3410);
PAINT ORANGE (-2690 3410);
FORCEPROP 2 LASTPIN (-2700 3200) $PN L3
J 0
(-2690 3210);
DISPLAY 0.617021 (-2690 3210);
PAINT ORANGE (-2690 3210);
FORCEPROP 2 LASTPIN (-2700 3300) $PN L1
J 0
(-2690 3310);
DISPLAY 0.617021 (-2690 3310);
PAINT ORANGE (-2690 3310);
FORCEPROP 2 LASTPIN (-2700 3250) $PN F5
J 0
(-2690 3260);
DISPLAY 0.617021 (-2690 3260);
PAINT ORANGE (-2690 3260);
FORCEPROP 2 LASTPIN (-2700 3600) $PN G7
J 0
(-2690 3610);
DISPLAY 0.617021 (-2690 3610);
PAINT ORANGE (-2690 3610);
FORCEPROP 2 LASTPIN (-2700 3550) $PN J3
J 0
(-2690 3560);
DISPLAY 0.617021 (-2690 3560);
PAINT ORANGE (-2690 3560);
FORCEPROP 2 LASTPIN (-2700 3450) $PN K2
J 0
(-2690 3460);
DISPLAY 0.617021 (-2690 3460);
PAINT ORANGE (-2690 3460);
FORCEPROP 2 LASTPIN (-2700 2550) $PN P11
J 0
(-2690 2560);
DISPLAY 0.617021 (-2690 2560);
PAINT ORANGE (-2690 2560);
FORCEPROP 2 LASTPIN (-2700 1600) $PN AF61
J 0
(-2690 1610);
DISPLAY 0.617021 (-2690 1610);
PAINT ORANGE (-2690 1610);
FORCEPROP 2 LASTPIN (-2700 1650) $PN AC56
J 0
(-2690 1660);
DISPLAY 0.617021 (-2690 1660);
PAINT ORANGE (-2690 1660);
FORCEPROP 2 LASTPIN (-2700 1700) $PN AA58
J 0
(-2690 1710);
DISPLAY 0.617021 (-2690 1710);
PAINT ORANGE (-2690 1710);
FORCEPROP 2 LASTPIN (-2700 1750) $PN V11
J 0
(-2690 1760);
DISPLAY 0.617021 (-2690 1760);
PAINT ORANGE (-2690 1760);
FORCEPROP 2 LASTPIN (-2700 1800) $PN P37
J 0
(-2690 1810);
DISPLAY 0.617021 (-2690 1810);
PAINT ORANGE (-2690 1810);
FORCEPROP 2 LASTPIN (-2700 1850) $PN AG15
J 0
(-2690 1860);
DISPLAY 0.617021 (-2690 1860);
PAINT ORANGE (-2690 1860);
FORCEPROP 2 LASTPIN (-2700 1900) $PN AT69
J 0
(-2690 1910);
DISPLAY 0.617021 (-2690 1910);
PAINT ORANGE (-2690 1910);
FORCEPROP 2 LASTPIN (-2700 1950) $PN F8
J 0
(-2690 1960);
DISPLAY 0.617021 (-2690 1960);
PAINT ORANGE (-2690 1960);
FORCEPROP 2 LASTPIN (-2700 2000) $PN F69
J 0
(-2690 2010);
DISPLAY 0.617021 (-2690 2010);
PAINT ORANGE (-2690 2010);
FORCEPROP 2 LASTPIN (-2700 2050) $PN F66
J 0
(-2690 2060);
DISPLAY 0.617021 (-2690 2060);
PAINT ORANGE (-2690 2060);
FORCEPROP 2 LASTPIN (-2700 2100) $PN D8
J 0
(-2690 2110);
DISPLAY 0.617021 (-2690 2110);
PAINT ORANGE (-2690 2110);
FORCEPROP 2 LASTPIN (-2700 2150) $PN C18
J 0
(-2690 2160);
DISPLAY 0.617021 (-2690 2160);
PAINT ORANGE (-2690 2160);
FORCEPROP 2 LASTPIN (-2700 2200) $PN C68
J 0
(-2690 2210);
DISPLAY 0.617021 (-2690 2210);
PAINT ORANGE (-2690 2210);
FORCEPROP 2 LASTPIN (-5400 1600) $PN C67
J 2
(-5410 1610);
DISPLAY 0.617021 (-5410 1610);
PAINT ORANGE (-5410 1610);
FORCEPROP 2 LASTPIN (-5400 1650) $PN E18
J 2
(-5410 1660);
DISPLAY 0.617021 (-5410 1660);
PAINT ORANGE (-5410 1660);
FORCEPROP 2 LASTPIN (-5400 1700) $PN C6
J 2
(-5410 1710);
DISPLAY 0.617021 (-5410 1710);
PAINT ORANGE (-5410 1710);
FORCEPROP 2 LASTPIN (-5400 1800) $PN B10
J 2
(-5410 1810);
DISPLAY 0.617021 (-5410 1810);
PAINT ORANGE (-5410 1810);
FORCEPROP 2 LASTPIN (-5400 1850) $PN C11
J 2
(-5410 1860);
DISPLAY 0.617021 (-5410 1860);
PAINT ORANGE (-5410 1860);
FORCEPROP 2 LASTPIN (-5400 1900) $PN C9
J 2
(-5410 1910);
DISPLAY 0.617021 (-5410 1910);
PAINT ORANGE (-5410 1910);
FORCEPROP 2 LASTPIN (-5400 1950) $PN D10
J 2
(-5410 1960);
DISPLAY 0.617021 (-5410 1960);
PAINT ORANGE (-5410 1960);
FORCEPROP 2 LASTPIN (-5400 2000) $PN A11
J 2
(-5410 2010);
DISPLAY 0.617021 (-5410 2010);
PAINT ORANGE (-5410 2010);
FORCEPROP 2 LASTPIN (-5400 2050) $PN AT71
J 2
(-5410 2060);
DISPLAY 0.617021 (-5410 2060);
PAINT ORANGE (-5410 2060);
FORCEPROP 2 LASTPIN (-5400 2100) $PN P40
J 2
(-5410 2110);
DISPLAY 0.617021 (-5410 2110);
PAINT ORANGE (-5410 2110);
FORCEPROP 2 LASTPIN (-5400 2200) $PN P48
J 2
(-5410 2210);
DISPLAY 0.617021 (-5410 2210);
PAINT ORANGE (-5410 2210);
FORCEPROP 2 LASTPIN (-2700 3850) $PN BH24
J 0
(-2690 3860);
DISPLAY 0.617021 (-2690 3860);
PAINT ORANGE (-2690 3860);
FORCEPROP 2 LASTPIN (-2700 3900) $PN BG26
J 0
(-2690 3910);
DISPLAY 0.617021 (-2690 3910);
PAINT ORANGE (-2690 3910);
FORCEPROP 2 LASTPIN (-2700 3750) $PN BW3
J 0
(-2690 3760);
DISPLAY 0.617021 (-2690 3760);
PAINT ORANGE (-2690 3760);
FORCEPROP 2 LASTPIN (-2700 2950) $PN U20
J 0
(-2690 2960);
DISPLAY 0.617021 (-2690 2960);
PAINT ORANGE (-2690 2960);
FORCEPROP 2 LASTPIN (-2700 3000) $PN R20
J 0
(-2690 3010);
DISPLAY 0.617021 (-2690 3010);
PAINT ORANGE (-2690 3010);
FORCEPROP 2 LASTPIN (-2700 3050) $PN V22
J 0
(-2690 3060);
DISPLAY 0.617021 (-2690 3060);
PAINT ORANGE (-2690 3060);
FORCEPROP 2 LASTPIN (-5400 2300) $PN AG18
J 2
(-5410 2310);
DISPLAY 0.617021 (-5410 2310);
PAINT ORANGE (-5410 2310);
FORCEPROP 2 LASTPIN (-2700 2900) $PN H20
J 0
(-2690 2910);
DISPLAY 0.617021 (-2690 2910);
PAINT ORANGE (-2690 2910);
FORCEPROP 2 LASTPIN (-2700 2850) $PN U24
J 0
(-2690 2860);
DISPLAY 0.617021 (-2690 2860);
PAINT ORANGE (-2690 2860);
FORCEPROP 2 LASTPIN (-2700 2800) $PN V18
J 0
(-2690 2810);
DISPLAY 0.617021 (-2690 2810);
PAINT ORANGE (-2690 2810);
FORCEPROP 2 LASTPIN (-2700 2750) $PN K20
J 0
(-2690 2760);
DISPLAY 0.617021 (-2690 2760);
PAINT ORANGE (-2690 2760);
FORCEPROP 2 LASTPIN (-2700 2700) $PN M18
J 0
(-2690 2710);
DISPLAY 0.617021 (-2690 2710);
PAINT ORANGE (-2690 2710);
FORCEPROP 2 LASTPIN (-5400 2500) $PN AE11
J 2
(-5410 2510);
DISPLAY 0.617021 (-5410 2510);
PAINT ORANGE (-5410 2510);
FORCEPROP 2 LASTPIN (-5400 2450) $PN AE15
J 2
(-5410 2460);
DISPLAY 0.617021 (-5410 2460);
PAINT ORANGE (-5410 2460);
FORCEPROP 2 LASTPIN (-5400 2400) $PN AE18
J 2
(-5410 2410);
DISPLAY 0.617021 (-5410 2410);
PAINT ORANGE (-5410 2410);
FORCEPROP 2 LASTPIN (-5400 3750) $PN AJ3
J 2
(-5410 3760);
DISPLAY 0.617021 (-5410 3760);
PAINT ORANGE (-5410 3760);
FORCEPROP 2 LASTPIN (-5400 3850) $PN AH4
J 2
(-5410 3860);
DISPLAY 0.617021 (-5410 3860);
PAINT ORANGE (-5410 3860);
FORCEPROP 2 LASTPIN (-5400 3350) $PN AJ1
J 2
(-5410 3360);
DISPLAY 0.617021 (-5410 3360);
PAINT ORANGE (-5410 3360);
FORCEPROP 2 LASTPIN (-2700 3700) $PN C70
J 0
(-2690 3710);
DISPLAY 0.617021 (-2690 3710);
PAINT ORANGE (-2690 3710);
FORCEPROP 2 LASTPIN (-5400 2850) $PN AD20
J 2
(-5410 2860);
DISPLAY 0.617021 (-5410 2860);
PAINT ORANGE (-5410 2860);
FORCEPROP 2 LASTPIN (-5400 2550) $PN Y18
J 2
(-5410 2560);
DISPLAY 0.617021 (-5410 2560);
PAINT ORANGE (-5410 2560);
FORCEPROP 1 LAST MATERIAL IC
J 0
(-5350 4100);
DISPLAY 0.617021 (-5350 4100);
PAINT SKYBLUE (-5350 4100);
FORCEPROP 1 LAST LOCATION U7C1
J 0
(-5350 4200);
DISPLAY 0.617021 (-5350 4200);
PAINT AQUA (-5350 4200);
FORCEPROP 2 LASTPIN (-5400 3250) $PN AG11
J 2
(-5410 3260);
DISPLAY 0.617021 (-5410 3260);
PAINT ORANGE (-5410 3260);
FORCEPROP 2 LASTPIN (-5400 3100) $PN Y7
J 2
(-5410 3110);
DISPLAY 0.617021 (-5410 3110);
PAINT ORANGE (-5410 3110);
FORCEPROP 2 LASTPIN (-5400 3550) $PN AN3
J 2
(-5410 3560);
DISPLAY 0.617021 (-5410 3560);
PAINT ORANGE (-5410 3560);
FORCEPROP 2 LASTPIN (-5400 3500) $PN AL3
J 2
(-5410 3510);
DISPLAY 0.617021 (-5410 3510);
PAINT ORANGE (-5410 3510);
FORCEPROP 2 LASTPIN (-5400 3600) $PN AL1
J 2
(-5410 3610);
DISPLAY 0.617021 (-5410 3610);
PAINT ORANGE (-5410 3610);
FORCEPROP 2 LASTPIN (-5400 1750) $PN C5
J 2
(-5410 1760);
DISPLAY 0.617021 (-5410 1760);
PAINT ORANGE (-5410 1760);
FORCEPROP 2 LASTPIN (-5400 2600) $PN AA20
J 2
(-5410 2610);
DISPLAY 0.617021 (-5410 2610);
PAINT ORANGE (-5410 2610);
FORCEPROP 2 LASTPIN (-5400 2700) $PN AD9
J 2
(-5410 2710);
DISPLAY 0.617021 (-5410 2710);
PAINT ORANGE (-5410 2710);
FORCEPROP 2 LASTPIN (-5400 2750) $PN AD17
J 2
(-5410 2760);
DISPLAY 0.617021 (-5410 2760);
PAINT ORANGE (-5410 2760);
FORCEPROP 2 LASTPIN (-5400 2800) $PN AF20
J 2
(-5410 2810);
DISPLAY 0.617021 (-5410 2810);
PAINT ORANGE (-5410 2810);
FORCEPROP 2 LASTPIN (-2700 2650) $PN P18
J 0
(-2690 2660);
DISPLAY 0.617021 (-2690 2660);
PAINT ORANGE (-2690 2660);
FORCEPROP 1 LAST PART_NUMBER H91415-002
J 0
(-5350 1400);
DISPLAY 0.617021 (-5350 1400);
PAINT BLUE (-5350 1400);
FORCEPROP 2 LASTPIN (-2700 3150) $PN H4
J 0
(-2690 3160);
DISPLAY 0.617021 (-2690 3160);
PAINT ORANGE (-2690 3160);
FORCEPROP 2 LASTPIN (-5400 3000) $PN AA13
J 2
(-5410 3010);
DISPLAY 0.617021 (-5410 3010);
PAINT ORANGE (-5410 3010);
FORCEPROP 2 LASTPIN (-5400 3900) $PN AM4
J 2
(-5410 3910);
DISPLAY 0.617021 (-5410 3910);
PAINT ORANGE (-5410 3910);
FORCEPROP 2 LAST SEC_TYPE BGA1
J 0
(-5350 4250);
DISPLAY 1.021277 (-5350 4250);
PAINT ORANGE (-5350 4250);
DISPLAY INVISIBLE (-5350 4250);
FORCEPROP 2 LAST SEC 8
J 0
(-5350 4250);
DISPLAY 0.680851 (-5350 4250);
PAINT MONO (-5350 4250);
DISPLAY INVISIBLE (-5350 4250);
FORCEPROP 2 LAST CDS_LIB mstr_u_proc
J 0
(-4050 2800);
PAINT ORANGE (-4050 2800);
DISPLAY INVISIBLE (-4050 2800);
FORCEPROP 0 LAST BOM_COST SB
J 0
(-3900 5000);
DISPLAY 1.361702 (-3900 5000);
PAINT ORANGE (-3900 5000);
DISPLAY INVISIBLE (-3900 5000);
FORCEPROP 2 LAST CDS_LOCATION U7C1
J 0
(-5350 4200);
DISPLAY 0.617021 (-5350 4200);
PAINT AQUA (-5350 4200);
DISPLAY INVISIBLE (-5350 4200);
FORCEPROP 1 LAST PATH I34
J 0
(-4050 4100);
PAINT GREEN (-4050 4100);
DISPLAY INVISIBLE (-4050 4100);
FORCEPROP 0 LAST ROOM SB
J 0
(-3900 4900);
DISPLAY 1.361702 (-3900 4900);
PAINT ORANGE (-3900 4900);
DISPLAY INVISIBLE (-3900 4900);
FORCEPROP 1 LAST PACK_TYPE BGA1
J 0
(-5350 4200);
PAINT SKYBLUE (-5350 4200);
DISPLAY INVISIBLE (-5350 4200);
FORCEADD RES..2
(-7750 3675);
FORCEPROP 1 LAST LOCATION R8C26
J 0
(-7705 3800);
DISPLAY 0.617021 (-7705 3800);
PAINT AQUA (-7705 3800);
FORCEPROP 1 LASTPIN (-7750 3775) $PN 1
J 0
(-7745 3737);
DISPLAY 0.617021 (-7745 3737);
PAINT ORANGE (-7745 3737);
FORCEPROP 1 LASTPIN (-7750 3575) $PN 2
J 0
(-7745 3585);
DISPLAY 0.617021 (-7745 3585);
PAINT ORANGE (-7745 3585);
FORCEPROP 1 LAST PACK_TYPE 0402
J 0
(-7710 3500);
DISPLAY 0.617021 (-7710 3500);
PAINT SKYBLUE (-7710 3500);
FORCEPROP 1 LAST TOLERANCE 1%
J 0
(-7705 3700);
DISPLAY 0.617021 (-7705 3700);
PAINT SKYBLUE (-7705 3700);
FORCEPROP 1 LAST VALUE 100.0
J 0
(-7705 3750);
DISPLAY 0.617021 (-7705 3750);
PAINT SKYBLUE (-7705 3750);
FORCEPROP 1 LAST WATTAGE 1/16W
J 0
(-7710 3650);
DISPLAY 0.617021 (-7710 3650);
PAINT SKYBLUE (-7710 3650);
FORCEPROP 1 LAST MATERIAL CHIP
J 0
(-7710 3600);
DISPLAY 0.617021 (-7710 3600);
PAINT SKYBLUE (-7710 3600);
FORCEPROP 1 LAST PART_NUMBER G21796-017
J 0
(-7710 3550);
DISPLAY 0.617021 (-7710 3550);
PAINT BLUE (-7710 3550);
FORCEPROP 1 LAST PATH I35
J 0
(-7700 3850);
DISPLAY 0.978723 (-7700 3850);
PAINT WHITE (-7700 3850);
DISPLAY INVISIBLE (-7700 3850);
FORCEPROP 2 LAST CDS_LIB mstr_discrete
J 0
(-7750 3675);
PAINT ORANGE (-7750 3675);
DISPLAY INVISIBLE (-7750 3675);
FORCEPROP 2 LAST SEC 1
J 0
(-7700 3900);
DISPLAY 0.680851 (-7700 3900);
PAINT MONO (-7700 3900);
DISPLAY INVISIBLE (-7700 3900);
FORCEPROP 2 LAST SEC_TYPE 0402
J 0
(-7700 3900);
DISPLAY 1.021277 (-7700 3900);
PAINT ORANGE (-7700 3900);
DISPLAY INVISIBLE (-7700 3900);
FORCEPROP 0 LAST ROOM SB
J 0
(-7800 3875);
DISPLAY 1.021277 (-7800 3875);
PAINT ORANGE (-7800 3875);
DISPLAY INVISIBLE (-7800 3875);
FORCEPROP 2 LAST CDS_LOCATION R8C26
J 0
(-7800 3725);
DISPLAY 0.617021 (-7800 3725);
PAINT AQUA (-7800 3725);
DISPLAY INVISIBLE (-7800 3725);
FORCEADD RES..2
(-8075 2525);
FORCEPROP 1 LAST PACK_TYPE 0402
J 0
(-8035 2350);
DISPLAY 0.617021 (-8035 2350);
PAINT SKYBLUE (-8035 2350);
FORCEPROP 1 LASTPIN (-8075 2625) $PN 1
J 0
(-8070 2587);
DISPLAY 0.617021 (-8070 2587);
PAINT ORANGE (-8070 2587);
FORCEPROP 1 LASTPIN (-8075 2425) $PN 2
J 0
(-8070 2435);
DISPLAY 0.617021 (-8070 2435);
PAINT ORANGE (-8070 2435);
FORCEPROP 1 LAST WATTAGE 1/16W
J 0
(-8035 2500);
DISPLAY 0.617021 (-8035 2500);
PAINT SKYBLUE (-8035 2500);
FORCEPROP 1 LAST MATERIAL CHIP
J 0
(-8035 2450);
DISPLAY 0.617021 (-8035 2450);
PAINT SKYBLUE (-8035 2450);
FORCEPROP 1 LAST TOLERANCE 1%
J 0
(-8030 2550);
DISPLAY 0.617021 (-8030 2550);
PAINT SKYBLUE (-8030 2550);
FORCEPROP 1 LAST VALUE 10.0K
J 0
(-8030 2600);
DISPLAY 0.617021 (-8030 2600);
PAINT SKYBLUE (-8030 2600);
FORCEPROP 1 LAST LOCATION R3N10
J 0
(-8030 2650);
DISPLAY 0.617021 (-8030 2650);
PAINT AQUA (-8030 2650);
FORCEPROP 1 LAST PART_NUMBER G21796-016
J 0
(-8035 2400);
DISPLAY 0.617021 (-8035 2400);
PAINT BLUE (-8035 2400);
FORCEPROP 2 LAST CDS_LOCATION R3N10
J 0
(-8030 2650);
DISPLAY 0.617021 (-8030 2650);
PAINT AQUA (-8030 2650);
DISPLAY INVISIBLE (-8030 2650);
FORCEPROP 2 LAST SEC 1
J 0
(-8025 2750);
DISPLAY 0.680851 (-8025 2750);
PAINT MONO (-8025 2750);
DISPLAY INVISIBLE (-8025 2750);
FORCEPROP 2 LAST SEC_TYPE 0402
J 0
(-8025 2750);
DISPLAY 1.021277 (-8025 2750);
PAINT ORANGE (-8025 2750);
DISPLAY INVISIBLE (-8025 2750);
FORCEPROP 2 LAST CDS_LIB mstr_discrete
J 0
(-8075 2525);
PAINT ORANGE (-8075 2525);
DISPLAY INVISIBLE (-8075 2525);
FORCEPROP 1 LAST PATH I37
J 0
(-8025 2700);
DISPLAY 0.978723 (-8025 2700);
PAINT WHITE (-8025 2700);
DISPLAY INVISIBLE (-8025 2700);
FORCEPROP 0 LAST ROOM SB
J 0
(-8025 2750);
DISPLAY 1.021277 (-8025 2750);
PAINT ORANGE (-8025 2750);
DISPLAY INVISIBLE (-8025 2750);
FORCEADD GND..1
(-7750 3450);
FORCEPROP 3 LASTPIN (-7750 3500) SIG_NAME GND\g
J 0
(-7740 3510);
DISPLAY 0.659574 (-7740 3510);
PAINT MONO (-7740 3510);
DISPLAY INVISIBLE (-7740 3510);
FORCEPROP 1 LAST PATH I39
J 0
(-7675 3450);
DISPLAY 0.872340 (-7675 3450);
PAINT AQUA (-7675 3450);
DISPLAY INVISIBLE (-7675 3450);
FORCEPROP 1 LAST BODY_TYPE PLUMBING
J 0
(-7795 3407);
DISPLAY 0.340426 (-7795 3407);
PAINT GREEN (-7795 3407);
DISPLAY INVISIBLE (-7795 3407);
FORCEPROP 2 LAST CDS_LIB mstr_symbols
J 0
(-7750 3450);
PAINT ORANGE (-7750 3450);
DISPLAY INVISIBLE (-7750 3450);
FORCEPROP 1 LAST SIZE 1B
J 0
(-7675 3400);
DISPLAY 0.872340 (-7675 3400);
PAINT AQUA (-7675 3400);
DISPLAY INVISIBLE (-7675 3400);
FORCEPROP 1 LAST HDL_POWER GND
J 0
(-7750 3600);
DISPLAY 0.872340 (-7750 3600);
PAINT GREEN (-7750 3600);
DISPLAY INVISIBLE (-7750 3600);
FORCEPROP 1 LAST VOLTAGE 0.0V
J 0
(-7795 3407);
DISPLAY 0.340426 (-7795 3407);
PAINT SKYBLUE (-7795 3407);
DISPLAY INVISIBLE (-7795 3407);
FORCEADD P3V3_STBY..1
(-8075 2750);
FORCEPROP 3 LASTPIN (-8075 2700) SIG_NAME P3V3_STBY\g
J 0
(-8065 2710);
DISPLAY 0.659574 (-8065 2710);
PAINT MONO (-8065 2710);
DISPLAY INVISIBLE (-8065 2710);
FORCEPROP 2 LAST CDS_LIB mstr_symbols
J 0
(-8075 2750);
PAINT ORANGE (-8075 2750);
DISPLAY INVISIBLE (-8075 2750);
FORCEPROP 1 LAST SIZE 1B
J 0
(-8030 2772);
DISPLAY 0.340426 (-8030 2772);
PAINT GREEN (-8030 2772);
DISPLAY INVISIBLE (-8030 2772);
FORCEPROP 1 LAST BODY_TYPE PLUMBING
J 0
(-8120 2707);
DISPLAY 0.340426 (-8120 2707);
PAINT GREEN (-8120 2707);
DISPLAY INVISIBLE (-8120 2707);
FORCEPROP 1 LAST PATH I40
J 0
(-8030 2752);
DISPLAY 0.340426 (-8030 2752);
PAINT GREEN (-8030 2752);
DISPLAY INVISIBLE (-8030 2752);
FORCEPROP 1 LAST HDL_POWER P3V3_STBY
J 0
(-8375 2625);
DISPLAY 0.872340 (-8375 2625);
PAINT ORANGE (-8375 2625);
DISPLAY INVISIBLE (-8375 2625);
FORCEPROP 1 LAST VOLTAGE 3.3V
J 0
(-8120 2707);
DISPLAY 0.340426 (-8120 2707);
PAINT SKYBLUE (-8120 2707);
DISPLAY INVISIBLE (-8120 2707);
FORCEADD OFFPAGE..4
(-1375 2850);
FORCEPROP 2 LAST $XR1 147 
J 0
(-1069 2850);
DISPLAY 0.638298 (-1069 2850);
PAINT MONO (-1069 2850);
FORCEPROP 2 LAST $XR0 125 
J 0
(-1189 2850);
DISPLAY 0.638298 (-1189 2850);
PAINT MONO (-1189 2850);
FORCEPROP 2 LAST PATH I41
J 0
(-1325 2925);
DISPLAY 1.021277 (-1325 2925);
PAINT ORANGE (-1325 2925);
DISPLAY INVISIBLE (-1325 2925);
FORCEPROP 1 LAST COMMENT_BODY TRUE
J 0
(-1400 2750);
DISPLAY 0.872340 (-1400 2750);
PAINT GREEN (-1400 2750);
DISPLAY INVISIBLE (-1400 2750);
FORCEPROP 1 LAST OFFPAGE TRUE
J 0
(-1050 2725);
DISPLAY 0.872340 (-1050 2725);
PAINT GREEN (-1050 2725);
DISPLAY INVISIBLE (-1050 2725);
FORCEPROP 2 LAST CDS_LIB mstr_standard
J 0
(-1375 2850);
PAINT MONO (-1375 2850);
DISPLAY INVISIBLE (-1375 2850);
FORCEADD OFFPAGE..2
(-1375 2150);
FORCEPROP 2 LAST $XR1 191 
J 0
(-1066 2150);
DISPLAY 0.638298 (-1066 2150);
PAINT MONO (-1066 2150);
FORCEPROP 2 LAST $XR0 133 
J 0
(-1186 2150);
DISPLAY 0.638298 (-1186 2150);
PAINT MONO (-1186 2150);
FORCEPROP 2 LAST PATH I42
J 0
(-1200 2225);
DISPLAY 1.021277 (-1200 2225);
PAINT ORANGE (-1200 2225);
DISPLAY INVISIBLE (-1200 2225);
FORCEPROP 1 LAST COMMENT_BODY TRUE
J 0
(-1420 2055);
DISPLAY 1.404255 (-1420 2055);
PAINT GREEN (-1420 2055);
DISPLAY INVISIBLE (-1420 2055);
FORCEPROP 1 LAST OFFPAGE TRUE
J 0
(-1050 2025);
PAINT GREEN (-1050 2025);
DISPLAY INVISIBLE (-1050 2025);
FORCEPROP 2 LAST CDS_LIB mstr_standard
J 0
(-1375 2150);
PAINT MONO (-1375 2150);
DISPLAY INVISIBLE (-1375 2150);
FORCEADD OFFPAGE..2
(-1375 2100);
FORCEPROP 2 LAST $XR1 191 
J 0
(-1066 2100);
DISPLAY 0.638298 (-1066 2100);
PAINT MONO (-1066 2100);
FORCEPROP 2 LAST $XR0 133 
J 0
(-1186 2100);
DISPLAY 0.638298 (-1186 2100);
PAINT MONO (-1186 2100);
FORCEPROP 2 LAST PATH I43
J 0
(-1200 2175);
DISPLAY 1.021277 (-1200 2175);
PAINT ORANGE (-1200 2175);
DISPLAY INVISIBLE (-1200 2175);
FORCEPROP 1 LAST COMMENT_BODY TRUE
J 0
(-1420 2005);
DISPLAY 1.404255 (-1420 2005);
PAINT GREEN (-1420 2005);
DISPLAY INVISIBLE (-1420 2005);
FORCEPROP 1 LAST OFFPAGE TRUE
J 0
(-1050 1975);
PAINT GREEN (-1050 1975);
DISPLAY INVISIBLE (-1050 1975);
FORCEPROP 2 LAST CDS_LIB mstr_standard
J 0
(-1375 2100);
PAINT MONO (-1375 2100);
DISPLAY INVISIBLE (-1375 2100);
FORCEADD OFFPAGE..2
(-1375 3400);
FORCEPROP 2 LAST $XR0 184 
J 0
(-1186 3400);
DISPLAY 0.638298 (-1186 3400);
PAINT MONO (-1186 3400);
FORCEPROP 2 LAST PATH I49
J 0
(-1200 3475);
DISPLAY 1.021277 (-1200 3475);
PAINT ORANGE (-1200 3475);
DISPLAY INVISIBLE (-1200 3475);
FORCEPROP 1 LAST COMMENT_BODY TRUE
J 0
(-1420 3305);
DISPLAY 1.404255 (-1420 3305);
PAINT GREEN (-1420 3305);
DISPLAY INVISIBLE (-1420 3305);
FORCEPROP 1 LAST OFFPAGE TRUE
J 0
(-1050 3275);
PAINT GREEN (-1050 3275);
DISPLAY INVISIBLE (-1050 3275);
FORCEPROP 2 LAST CDS_LIB mstr_standard
J 0
(-1375 3400);
PAINT MONO (-1375 3400);
DISPLAY INVISIBLE (-1375 3400);
FORCEADD OFFPAGE..1
(-6600 2650);
FORCEPROP 2 LAST $XR1 133 
J 0
(-6972 2650);
DISPLAY 0.638298 (-6972 2650);
PAINT MONO (-6972 2650);
FORCEPROP 2 LAST $XR0 109 
J 0
(-6852 2650);
DISPLAY 0.638298 (-6852 2650);
PAINT MONO (-6852 2650);
FORCEPROP 2 LAST PATH I50
J 0
(-6550 2725);
DISPLAY 1.021277 (-6550 2725);
PAINT ORANGE (-6550 2725);
DISPLAY INVISIBLE (-6550 2725);
FORCEPROP 1 LAST COMMENT_BODY TRUE
J 0
(-6475 2550);
DISPLAY 0.872340 (-6475 2550);
PAINT GREEN (-6475 2550);
DISPLAY INVISIBLE (-6475 2550);
FORCEPROP 1 LAST OFFPAGE TRUE
J 0
(-6275 2525);
DISPLAY 0.872340 (-6275 2525);
PAINT GREEN (-6275 2525);
DISPLAY INVISIBLE (-6275 2525);
FORCEPROP 2 LAST CDS_LIB mstr_standard
J 0
(-6600 2650);
PAINT MONO (-6600 2650);
DISPLAY INVISIBLE (-6600 2650);
FORCEADD OFFPAGE..1
(-6600 2600);
FORCEPROP 2 LAST $XR0 133 
J 0
(-6852 2600);
DISPLAY 0.638298 (-6852 2600);
PAINT MONO (-6852 2600);
FORCEPROP 2 LAST PATH I51
J 0
(-6550 2675);
DISPLAY 1.021277 (-6550 2675);
PAINT ORANGE (-6550 2675);
DISPLAY INVISIBLE (-6550 2675);
FORCEPROP 1 LAST COMMENT_BODY TRUE
J 0
(-6475 2500);
DISPLAY 0.872340 (-6475 2500);
PAINT GREEN (-6475 2500);
DISPLAY INVISIBLE (-6475 2500);
FORCEPROP 1 LAST OFFPAGE TRUE
J 0
(-6275 2475);
DISPLAY 0.872340 (-6275 2475);
PAINT GREEN (-6275 2475);
DISPLAY INVISIBLE (-6275 2475);
FORCEPROP 2 LAST CDS_LIB mstr_standard
J 0
(-6600 2600);
PAINT MONO (-6600 2600);
DISPLAY INVISIBLE (-6600 2600);
FORCEADD OFFPAGE..1
(-6600 2550);
FORCEPROP 2 LAST $XR0 133 
J 0
(-6852 2550);
DISPLAY 0.638298 (-6852 2550);
PAINT MONO (-6852 2550);
FORCEPROP 2 LAST PATH I52
J 0
(-6550 2625);
DISPLAY 1.021277 (-6550 2625);
PAINT ORANGE (-6550 2625);
DISPLAY INVISIBLE (-6550 2625);
FORCEPROP 1 LAST COMMENT_BODY TRUE
J 0
(-6475 2450);
DISPLAY 0.872340 (-6475 2450);
PAINT GREEN (-6475 2450);
DISPLAY INVISIBLE (-6475 2450);
FORCEPROP 1 LAST OFFPAGE TRUE
J 0
(-6275 2425);
DISPLAY 0.872340 (-6275 2425);
PAINT GREEN (-6275 2425);
DISPLAY INVISIBLE (-6275 2425);
FORCEPROP 2 LAST CDS_LIB mstr_standard
J 0
(-6600 2550);
PAINT MONO (-6600 2550);
DISPLAY INVISIBLE (-6600 2550);
FORCEADD OFFPAGE..1
(-6600 2500);
FORCEPROP 2 LAST $XR0 133 
J 0
(-6852 2500);
DISPLAY 0.638298 (-6852 2500);
PAINT MONO (-6852 2500);
FORCEPROP 2 LAST PATH I53
J 0
(-6550 2575);
DISPLAY 1.021277 (-6550 2575);
PAINT ORANGE (-6550 2575);
DISPLAY INVISIBLE (-6550 2575);
FORCEPROP 1 LAST COMMENT_BODY TRUE
J 0
(-6475 2400);
DISPLAY 0.872340 (-6475 2400);
PAINT GREEN (-6475 2400);
DISPLAY INVISIBLE (-6475 2400);
FORCEPROP 1 LAST OFFPAGE TRUE
J 0
(-6275 2375);
DISPLAY 0.872340 (-6275 2375);
PAINT GREEN (-6275 2375);
DISPLAY INVISIBLE (-6275 2375);
FORCEPROP 2 LAST CDS_LIB mstr_standard
J 0
(-6600 2500);
PAINT MONO (-6600 2500);
DISPLAY INVISIBLE (-6600 2500);
FORCEADD OFFPAGE..1
(-6600 2450);
FORCEPROP 2 LAST $XR0 133 
J 0
(-6852 2450);
DISPLAY 0.638298 (-6852 2450);
PAINT MONO (-6852 2450);
FORCEPROP 2 LAST CDS_LIB mstr_standard
J 0
(-6600 2450);
PAINT MONO (-6600 2450);
DISPLAY INVISIBLE (-6600 2450);
FORCEPROP 2 LAST PATH I54
J 0
(-6550 2525);
DISPLAY 1.021277 (-6550 2525);
PAINT ORANGE (-6550 2525);
DISPLAY INVISIBLE (-6550 2525);
FORCEPROP 1 LAST OFFPAGE TRUE
J 0
(-6275 2325);
DISPLAY 0.872340 (-6275 2325);
PAINT GREEN (-6275 2325);
DISPLAY INVISIBLE (-6275 2325);
FORCEPROP 1 LAST COMMENT_BODY TRUE
J 0
(-6475 2350);
DISPLAY 0.872340 (-6475 2350);
PAINT GREEN (-6475 2350);
DISPLAY INVISIBLE (-6475 2350);
FORCEADD OFFPAGE..2
(-1375 3300);
FORCEPROP 2 LAST $XR1 154 
J 0
(-1066 3300);
DISPLAY 0.638298 (-1066 3300);
PAINT MONO (-1066 3300);
FORCEPROP 2 LAST $XR0 125 
J 0
(-1186 3300);
DISPLAY 0.638298 (-1186 3300);
PAINT MONO (-1186 3300);
FORCEPROP 2 LAST PATH I6
J 0
(-1200 3375);
DISPLAY 1.021277 (-1200 3375);
PAINT ORANGE (-1200 3375);
DISPLAY INVISIBLE (-1200 3375);
FORCEPROP 1 LAST COMMENT_BODY TRUE
J 0
(-1420 3205);
DISPLAY 0.872340 (-1420 3205);
PAINT GREEN (-1420 3205);
DISPLAY INVISIBLE (-1420 3205);
FORCEPROP 1 LAST OFFPAGE TRUE
J 0
(-1050 3175);
DISPLAY 0.872340 (-1050 3175);
PAINT GREEN (-1050 3175);
DISPLAY INVISIBLE (-1050 3175);
FORCEPROP 2 LAST CDS_LIB mstr_standard
J 0
(-1375 3300);
PAINT ORANGE (-1375 3300);
DISPLAY INVISIBLE (-1375 3300);
FORCEADD OFFPAGE..2
(-1375 3250);
FORCEPROP 2 LAST $XR2 154 
J 0
(-946 3250);
DISPLAY 0.638298 (-946 3250);
PAINT MONO (-946 3250);
FORCEPROP 2 LAST $XR1 125 
J 0
(-1066 3250);
DISPLAY 0.638298 (-1066 3250);
PAINT MONO (-1066 3250);
FORCEPROP 2 LAST $XR0 111 
J 0
(-1186 3250);
DISPLAY 0.638298 (-1186 3250);
PAINT MONO (-1186 3250);
FORCEPROP 2 LAST PATH I7
J 0
(-1200 3325);
DISPLAY 1.021277 (-1200 3325);
PAINT ORANGE (-1200 3325);
DISPLAY INVISIBLE (-1200 3325);
FORCEPROP 1 LAST COMMENT_BODY TRUE
J 0
(-1420 3155);
DISPLAY 0.872340 (-1420 3155);
PAINT GREEN (-1420 3155);
DISPLAY INVISIBLE (-1420 3155);
FORCEPROP 1 LAST OFFPAGE TRUE
J 0
(-1050 3125);
DISPLAY 0.872340 (-1050 3125);
PAINT GREEN (-1050 3125);
DISPLAY INVISIBLE (-1050 3125);
FORCEPROP 2 LAST CDS_LIB mstr_standard
J 0
(-1375 3250);
PAINT ORANGE (-1375 3250);
DISPLAY INVISIBLE (-1375 3250);
FORCEADD OFFPAGE..2
(-7325 1175);
FORCEPROP 2 LAST $XR1 121 
J 0
(-7016 1175);
DISPLAY 0.638298 (-7016 1175);
PAINT MONO (-7016 1175);
FORCEPROP 2 LAST $XR0 101 
J 0
(-7136 1175);
DISPLAY 0.638298 (-7136 1175);
PAINT MONO (-7136 1175);
FORCEPROP 2 LAST CDS_LIB mstr_standard
J 0
(-7325 1175);
PAINT ORANGE (-7325 1175);
DISPLAY INVISIBLE (-7325 1175);
FORCEPROP 1 LAST OFFPAGE TRUE
J 0
(-7000 1050);
DISPLAY 0.872340 (-7000 1050);
PAINT GREEN (-7000 1050);
DISPLAY INVISIBLE (-7000 1050);
FORCEPROP 1 LAST COMMENT_BODY TRUE
J 0
(-7370 1080);
DISPLAY 0.872340 (-7370 1080);
PAINT GREEN (-7370 1080);
DISPLAY INVISIBLE (-7370 1080);
FORCEPROP 2 LAST PATH I72
J 0
(-7150 1250);
DISPLAY 1.021277 (-7150 1250);
PAINT ORANGE (-7150 1250);
DISPLAY INVISIBLE (-7150 1250);
FORCEADD RES..2
(-8125 950);
FORCEPROP 1 LAST LOCATION R7C20
J 0
(-8080 1075);
DISPLAY 0.617021 (-8080 1075);
PAINT AQUA (-8080 1075);
FORCEPROP 1 LASTPIN (-8125 1050) $PN 1
J 0
(-8120 1012);
DISPLAY 0.617021 (-8120 1012);
PAINT ORANGE (-8120 1012);
FORCEPROP 1 LASTPIN (-8125 850) $PN 2
J 0
(-8120 860);
DISPLAY 0.617021 (-8120 860);
PAINT ORANGE (-8120 860);
FORCEPROP 1 LAST PACK_TYPE 0402
J 0
(-8085 775);
DISPLAY 0.617021 (-8085 775);
PAINT SKYBLUE (-8085 775);
FORCEPROP 1 LAST TOLERANCE 1%
J 0
(-8080 975);
DISPLAY 0.617021 (-8080 975);
PAINT SKYBLUE (-8080 975);
FORCEPROP 1 LAST VALUE 10.0K
J 0
(-8080 1025);
DISPLAY 0.617021 (-8080 1025);
PAINT SKYBLUE (-8080 1025);
FORCEPROP 1 LAST PART_NUMBER G21796-016
J 0
(-8085 825);
DISPLAY 0.617021 (-8085 825);
PAINT BLUE (-8085 825);
FORCEPROP 1 LAST MATERIAL CHIP
J 0
(-8085 875);
DISPLAY 0.617021 (-8085 875);
PAINT SKYBLUE (-8085 875);
FORCEPROP 1 LAST WATTAGE 1/16W
J 0
(-8085 925);
DISPLAY 0.617021 (-8085 925);
PAINT SKYBLUE (-8085 925);
FORCEPROP 1 LAST PATH I73
J 0
(-8075 1125);
DISPLAY 0.978723 (-8075 1125);
PAINT WHITE (-8075 1125);
DISPLAY INVISIBLE (-8075 1125);
FORCEPROP 2 LAST CDS_LIB mstr_discrete
J 0
(-8125 950);
PAINT ORANGE (-8125 950);
DISPLAY INVISIBLE (-8125 950);
FORCEPROP 2 LAST SEC_TYPE 0402
J 0
(-8075 1175);
DISPLAY 1.021277 (-8075 1175);
PAINT ORANGE (-8075 1175);
DISPLAY INVISIBLE (-8075 1175);
FORCEPROP 2 LAST BOM_COST NT_GBE_BASE
J 0
(-8075 1175);
DISPLAY 1.021277 (-8075 1175);
PAINT ORANGE (-8075 1175);
DISPLAY INVISIBLE (-8075 1175);
FORCEPROP 2 LAST SEC 1
J 0
(-8075 1175);
DISPLAY 0.680851 (-8075 1175);
PAINT MONO (-8075 1175);
DISPLAY INVISIBLE (-8075 1175);
FORCEPROP 2 LAST CDS_LOCATION R7C20
J 0
(-8080 1075);
DISPLAY 0.617021 (-8080 1075);
PAINT AQUA (-8080 1075);
DISPLAY INVISIBLE (-8080 1075);
FORCEPROP 2 LAST ROOM NIC_SPRV
J 0
(-8075 1125);
DISPLAY 1.021277 (-8075 1125);
PAINT ORANGE (-8075 1125);
DISPLAY INVISIBLE (-8075 1125);
FORCEADD GND..1
(-8125 675);
FORCEPROP 3 LASTPIN (-8125 725) SIG_NAME GND\g
J 0
(-8115 735);
DISPLAY 0.659574 (-8115 735);
PAINT MONO (-8115 735);
DISPLAY INVISIBLE (-8115 735);
FORCEPROP 1 LAST PATH I74
J 0
(-8050 675);
DISPLAY 0.872340 (-8050 675);
PAINT AQUA (-8050 675);
DISPLAY INVISIBLE (-8050 675);
FORCEPROP 1 LAST BODY_TYPE PLUMBING
J 0
(-8170 632);
DISPLAY 0.340426 (-8170 632);
PAINT GREEN (-8170 632);
DISPLAY INVISIBLE (-8170 632);
FORCEPROP 2 LAST CDS_LIB mstr_symbols
J 0
(-8125 675);
PAINT ORANGE (-8125 675);
DISPLAY INVISIBLE (-8125 675);
FORCEPROP 1 LAST SIZE 1B
J 0
(-8050 625);
DISPLAY 0.872340 (-8050 625);
PAINT AQUA (-8050 625);
DISPLAY INVISIBLE (-8050 625);
FORCEPROP 1 LAST HDL_POWER GND
J 0
(-8125 825);
DISPLAY 0.872340 (-8125 825);
PAINT GREEN (-8125 825);
DISPLAY INVISIBLE (-8125 825);
FORCEPROP 1 LAST VOLTAGE 0.0V
J 0
(-8170 632);
DISPLAY 0.340426 (-8170 632);
PAINT SKYBLUE (-8170 632);
DISPLAY INVISIBLE (-8170 632);
FORCEADD OFFPAGE..1
(-6600 3050);
FORCEPROP 2 LAST $XR0 152 
J 0
(-6852 3050);
DISPLAY 0.638298 (-6852 3050);
PAINT MONO (-6852 3050);
FORCEPROP 2 LAST PATH I75
J 0
(-6875 3100);
DISPLAY 1.021277 (-6875 3100);
PAINT ORANGE (-6875 3100);
DISPLAY INVISIBLE (-6875 3100);
FORCEPROP 1 LAST COMMENT_BODY TRUE
J 0
(-6475 2950);
DISPLAY 0.872340 (-6475 2950);
PAINT GREEN (-6475 2950);
DISPLAY INVISIBLE (-6475 2950);
FORCEPROP 1 LAST OFFPAGE TRUE
J 0
(-6275 2925);
DISPLAY 0.872340 (-6275 2925);
PAINT GREEN (-6275 2925);
DISPLAY INVISIBLE (-6275 2925);
FORCEPROP 2 LAST CDS_LIB mstr_standard
J 0
(-6600 3050);
PAINT ORANGE (-6600 3050);
DISPLAY INVISIBLE (-6600 3050);
FORCEADD OFFPAGE..1
(-6600 2900);
FORCEPROP 2 LAST $XR0 152 
J 0
(-6852 2900);
DISPLAY 0.638298 (-6852 2900);
PAINT MONO (-6852 2900);
FORCEPROP 2 LAST PATH I76
J 0
(-6850 2950);
DISPLAY 1.021277 (-6850 2950);
PAINT ORANGE (-6850 2950);
DISPLAY INVISIBLE (-6850 2950);
FORCEPROP 1 LAST COMMENT_BODY TRUE
J 0
(-6475 2800);
DISPLAY 0.872340 (-6475 2800);
PAINT GREEN (-6475 2800);
DISPLAY INVISIBLE (-6475 2800);
FORCEPROP 1 LAST OFFPAGE TRUE
J 0
(-6275 2775);
DISPLAY 0.872340 (-6275 2775);
PAINT GREEN (-6275 2775);
DISPLAY INVISIBLE (-6275 2775);
FORCEPROP 2 LAST CDS_LIB mstr_standard
J 0
(-6600 2900);
PAINT ORANGE (-6600 2900);
DISPLAY INVISIBLE (-6600 2900);
FORCEADD OFFPAGE..1
(-6600 2950);
FORCEPROP 2 LAST $XR0 152 
J 0
(-6852 2950);
DISPLAY 0.638298 (-6852 2950);
PAINT MONO (-6852 2950);
FORCEPROP 2 LAST PATH I77
J 0
(-6850 3000);
DISPLAY 1.021277 (-6850 3000);
PAINT ORANGE (-6850 3000);
DISPLAY INVISIBLE (-6850 3000);
FORCEPROP 1 LAST COMMENT_BODY TRUE
J 0
(-6475 2850);
DISPLAY 0.872340 (-6475 2850);
PAINT GREEN (-6475 2850);
DISPLAY INVISIBLE (-6475 2850);
FORCEPROP 1 LAST OFFPAGE TRUE
J 0
(-6275 2825);
DISPLAY 0.872340 (-6275 2825);
PAINT GREEN (-6275 2825);
DISPLAY INVISIBLE (-6275 2825);
FORCEPROP 2 LAST CDS_LIB mstr_standard
J 0
(-6600 2950);
PAINT ORANGE (-6600 2950);
DISPLAY INVISIBLE (-6600 2950);
FORCEADD OFFPAGE..1
(-6600 3000);
FORCEPROP 2 LAST $XR0 152 
J 0
(-6852 3000);
DISPLAY 0.638298 (-6852 3000);
PAINT MONO (-6852 3000);
FORCEPROP 2 LAST PATH I78
J 0
(-6875 3050);
DISPLAY 1.021277 (-6875 3050);
PAINT ORANGE (-6875 3050);
DISPLAY INVISIBLE (-6875 3050);
FORCEPROP 1 LAST COMMENT_BODY TRUE
J 0
(-6475 2900);
DISPLAY 0.872340 (-6475 2900);
PAINT GREEN (-6475 2900);
DISPLAY INVISIBLE (-6475 2900);
FORCEPROP 1 LAST OFFPAGE TRUE
J 0
(-6275 2875);
DISPLAY 0.872340 (-6275 2875);
PAINT GREEN (-6275 2875);
DISPLAY INVISIBLE (-6275 2875);
FORCEPROP 2 LAST CDS_LIB mstr_standard
J 0
(-6600 3000);
PAINT ORANGE (-6600 3000);
DISPLAY INVISIBLE (-6600 3000);
FORCEADD OFFPAGE..1
(-6600 3250);
FORCEPROP 2 LAST $XR0 93 
J 0
(-6821 3250);
DISPLAY 0.638298 (-6821 3250);
PAINT MONO (-6821 3250);
FORCEPROP 2 LAST PATH I79
J 0
(-6850 3300);
DISPLAY 1.021277 (-6850 3300);
PAINT ORANGE (-6850 3300);
DISPLAY INVISIBLE (-6850 3300);
FORCEPROP 1 LAST COMMENT_BODY TRUE
J 0
(-6475 3150);
DISPLAY 1.404255 (-6475 3150);
PAINT PEACH (-6475 3150);
DISPLAY INVISIBLE (-6475 3150);
FORCEPROP 1 LAST OFFPAGE TRUE
J 0
(-6275 3125);
PAINT GREEN (-6275 3125);
DISPLAY INVISIBLE (-6275 3125);
FORCEPROP 2 LAST CDS_LIB mstr_standard
J 0
(-6600 3250);
PAINT ORANGE (-6600 3250);
DISPLAY INVISIBLE (-6600 3250);
FORCEADD OFFPAGE..4
(-1375 3200);
FORCEPROP 2 LAST $XR1 184 
J 0
(-1069 3200);
DISPLAY 0.638298 (-1069 3200);
PAINT MONO (-1069 3200);
FORCEPROP 2 LAST $XR0 154 
J 0
(-1189 3200);
DISPLAY 0.638298 (-1189 3200);
PAINT MONO (-1189 3200);
FORCEPROP 2 LAST PATH I8
J 0
(-1200 3275);
DISPLAY 1.021277 (-1200 3275);
PAINT ORANGE (-1200 3275);
DISPLAY INVISIBLE (-1200 3275);
FORCEPROP 1 LAST COMMENT_BODY TRUE
J 0
(-1400 3100);
DISPLAY 0.872340 (-1400 3100);
PAINT GREEN (-1400 3100);
DISPLAY INVISIBLE (-1400 3100);
FORCEPROP 1 LAST OFFPAGE TRUE
J 0
(-1050 3075);
DISPLAY 0.872340 (-1050 3075);
PAINT GREEN (-1050 3075);
DISPLAY INVISIBLE (-1050 3075);
FORCEPROP 2 LAST CDS_LIB mstr_standard
J 0
(-1375 3200);
PAINT ORANGE (-1375 3200);
DISPLAY INVISIBLE (-1375 3200);
FORCEADD OFFPAGE..1
(-6600 3200);
FORCEPROP 2 LAST $XR0 93 
J 0
(-6821 3200);
DISPLAY 0.638298 (-6821 3200);
PAINT MONO (-6821 3200);
FORCEPROP 2 LAST PATH I80
J 0
(-6800 3250);
DISPLAY 1.021277 (-6800 3250);
PAINT ORANGE (-6800 3250);
DISPLAY INVISIBLE (-6800 3250);
FORCEPROP 1 LAST COMMENT_BODY TRUE
J 0
(-6475 3100);
DISPLAY 1.404255 (-6475 3100);
PAINT PEACH (-6475 3100);
DISPLAY INVISIBLE (-6475 3100);
FORCEPROP 1 LAST OFFPAGE TRUE
J 0
(-6275 3075);
PAINT GREEN (-6275 3075);
DISPLAY INVISIBLE (-6275 3075);
FORCEPROP 2 LAST CDS_LIB mstr_standard
J 0
(-6600 3200);
PAINT ORANGE (-6600 3200);
DISPLAY INVISIBLE (-6600 3200);
FORCEADD OFFPAGE..1
(-6600 3100);
FORCEPROP 2 LAST $XR0 93 
J 0
(-6821 3100);
DISPLAY 0.638298 (-6821 3100);
PAINT MONO (-6821 3100);
FORCEPROP 2 LAST PATH I85
J 0
(-6800 3150);
DISPLAY 1.021277 (-6800 3150);
PAINT ORANGE (-6800 3150);
DISPLAY INVISIBLE (-6800 3150);
FORCEPROP 1 LAST COMMENT_BODY TRUE
J 0
(-6475 3000);
DISPLAY 1.404255 (-6475 3000);
PAINT PEACH (-6475 3000);
DISPLAY INVISIBLE (-6475 3000);
FORCEPROP 1 LAST OFFPAGE TRUE
J 0
(-6275 2975);
PAINT GREEN (-6275 2975);
DISPLAY INVISIBLE (-6275 2975);
FORCEPROP 2 LAST CDS_LIB mstr_standard
J 0
(-6600 3100);
PAINT MONO (-6600 3100);
DISPLAY INVISIBLE (-6600 3100);
FORCEADD OFFPAGE..1
(-6600 3150);
FORCEPROP 2 LAST $XR0 93 
J 0
(-6821 3150);
DISPLAY 0.638298 (-6821 3150);
PAINT MONO (-6821 3150);
FORCEPROP 2 LAST PATH I86
J 0
(-6850 3200);
DISPLAY 1.021277 (-6850 3200);
PAINT ORANGE (-6850 3200);
DISPLAY INVISIBLE (-6850 3200);
FORCEPROP 1 LAST COMMENT_BODY TRUE
J 0
(-6475 3050);
DISPLAY 1.404255 (-6475 3050);
PAINT PEACH (-6475 3050);
DISPLAY INVISIBLE (-6475 3050);
FORCEPROP 1 LAST OFFPAGE TRUE
J 0
(-6275 3025);
PAINT GREEN (-6275 3025);
DISPLAY INVISIBLE (-6275 3025);
FORCEPROP 2 LAST CDS_LIB mstr_standard
J 0
(-6600 3150);
PAINT MONO (-6600 3150);
DISPLAY INVISIBLE (-6600 3150);
FORCEADD OFFPAGE..1
(-6600 2750);
FORCEPROP 2 LAST $XR1 250 
J 0
(-6972 2750);
DISPLAY 0.638298 (-6972 2750);
PAINT MONO (-6972 2750);
FORCEPROP 2 LAST $XR0 133 
J 0
(-6852 2750);
DISPLAY 0.638298 (-6852 2750);
PAINT MONO (-6852 2750);
FORCEPROP 2 LAST PATH I87
J 0
(-6550 2825);
DISPLAY 1.021277 (-6550 2825);
PAINT ORANGE (-6550 2825);
DISPLAY INVISIBLE (-6550 2825);
FORCEPROP 1 LAST COMMENT_BODY TRUE
J 0
(-6475 2650);
DISPLAY 0.872340 (-6475 2650);
PAINT GREEN (-6475 2650);
DISPLAY INVISIBLE (-6475 2650);
FORCEPROP 1 LAST OFFPAGE TRUE
J 0
(-6275 2625);
DISPLAY 0.872340 (-6275 2625);
PAINT GREEN (-6275 2625);
DISPLAY INVISIBLE (-6275 2625);
FORCEPROP 2 LAST CDS_LIB mstr_standard
J 0
(-6600 2750);
PAINT ORANGE (-6600 2750);
DISPLAY INVISIBLE (-6600 2750);
FORCEADD OFFPAGE..1
(-6600 2700);
FORCEPROP 2 LAST $XR1 250 
J 0
(-6972 2700);
DISPLAY 0.638298 (-6972 2700);
PAINT MONO (-6972 2700);
FORCEPROP 2 LAST $XR0 133 
J 0
(-6852 2700);
DISPLAY 0.638298 (-6852 2700);
PAINT MONO (-6852 2700);
FORCEPROP 2 LAST PATH I88
J 0
(-6550 2775);
DISPLAY 1.021277 (-6550 2775);
PAINT ORANGE (-6550 2775);
DISPLAY INVISIBLE (-6550 2775);
FORCEPROP 1 LAST COMMENT_BODY TRUE
J 0
(-6475 2600);
DISPLAY 0.872340 (-6475 2600);
PAINT GREEN (-6475 2600);
DISPLAY INVISIBLE (-6475 2600);
FORCEPROP 1 LAST OFFPAGE TRUE
J 0
(-6275 2575);
DISPLAY 0.872340 (-6275 2575);
PAINT GREEN (-6275 2575);
DISPLAY INVISIBLE (-6275 2575);
FORCEPROP 2 LAST CDS_LIB mstr_standard
J 0
(-6600 2700);
PAINT ORANGE (-6600 2700);
DISPLAY INVISIBLE (-6600 2700);
FORCEADD RES..1
(-5100 550);
FORCEPROP 1 LASTPIN (-5200 550) $PN 1
J 0
(-5188 562);
DISPLAY 0.617021 (-5188 562);
PAINT ORANGE (-5188 562);
FORCEPROP 1 LAST TOLERANCE 5%
J 0
(-5125 500);
DISPLAY 0.617021 (-5125 500);
PAINT SKYBLUE (-5125 500);
FORCEPROP 1 LAST VALUE 0.0
J 2
(-5200 550);
DISPLAY 0.617021 (-5200 550);
PAINT SKYBLUE (-5200 550);
FORCEPROP 1 LAST LOCATION R3P3
J 0
(-5150 600);
DISPLAY 0.617021 (-5150 600);
PAINT AQUA (-5150 600);
FORCEPROP 1 LASTPIN (-5000 550) $PN 2
J 0
(-5038 562);
DISPLAY 0.617021 (-5038 562);
PAINT ORANGE (-5038 562);
FORCEPROP 1 LAST PACK_TYPE 0402
J 0
(-4900 500);
DISPLAY 0.617021 (-4900 500);
PAINT SKYBLUE (-4900 500);
FORCEPROP 1 LAST MATERIAL CHIP
J 0
(-5025 500);
DISPLAY 0.617021 (-5025 500);
PAINT SKYBLUE (-5025 500);
FORCEPROP 1 LAST PART_NUMBER G21497-005
J 0
(-5350 500);
DISPLAY 0.617021 (-5350 500);
PAINT BLUE (-5350 500);
FORCEPROP 1 LAST WATTAGE 1/16W
J 2
(-4625 500);
DISPLAY 0.617021 (-4625 500);
PAINT SKYBLUE (-4625 500);
FORCEPROP 2 LAST SEC_TYPE 0402
J 0
(-5150 750);
DISPLAY 1.021277 (-5150 750);
PAINT ORANGE (-5150 750);
DISPLAY INVISIBLE (-5150 750);
FORCEPROP 2 LAST CDS_LIB mstr_discrete
J 0
(-5100 550);
PAINT ORANGE (-5100 550);
DISPLAY INVISIBLE (-5100 550);
FORCEPROP 2 LAST SEC 1
J 0
(-5150 750);
DISPLAY 0.680851 (-5150 750);
PAINT MONO (-5150 750);
DISPLAY INVISIBLE (-5150 750);
FORCEPROP 2 LAST CDS_LOCATION R3P3
J 0
(-5400 550);
DISPLAY 0.617021 (-5400 550);
PAINT AQUA (-5400 550);
DISPLAY INVISIBLE (-5400 550);
FORCEPROP 0 LAST CDS_SEC 1
J 0
(-4975 600);
PAINT ORANGE (-4975 600);
DISPLAY INVISIBLE (-4975 600);
FORCEPROP 1 LAST PATH I89
J 0
(-5150 700);
DISPLAY 0.978723 (-5150 700);
PAINT WHITE (-5150 700);
DISPLAY INVISIBLE (-5150 700);
FORCEADD RES..1
(-5100 850);
FORCEPROP 1 LASTPIN (-5200 850) $PN 1
J 0
(-5188 862);
DISPLAY 0.617021 (-5188 862);
PAINT ORANGE (-5188 862);
FORCEPROP 1 LASTPIN (-5000 850) $PN 2
J 0
(-5038 862);
DISPLAY 0.617021 (-5038 862);
PAINT ORANGE (-5038 862);
FORCEPROP 1 LAST TOLERANCE 5%
J 0
(-5125 800);
DISPLAY 0.617021 (-5125 800);
PAINT SKYBLUE (-5125 800);
FORCEPROP 1 LAST VALUE 0.0
J 2
(-5200 850);
DISPLAY 0.617021 (-5200 850);
PAINT SKYBLUE (-5200 850);
FORCEPROP 1 LAST LOCATION R3P2
J 0
(-5150 900);
DISPLAY 0.617021 (-5150 900);
PAINT AQUA (-5150 900);
FORCEPROP 1 LAST PACK_TYPE 0402
J 0
(-4900 800);
DISPLAY 0.617021 (-4900 800);
PAINT SKYBLUE (-4900 800);
FORCEPROP 1 LAST PART_NUMBER G21497-005
J 0
(-5350 800);
DISPLAY 0.617021 (-5350 800);
PAINT BLUE (-5350 800);
FORCEPROP 1 LAST MATERIAL CHIP
J 0
(-5025 800);
DISPLAY 0.617021 (-5025 800);
PAINT SKYBLUE (-5025 800);
FORCEPROP 1 LAST WATTAGE 1/16W
J 2
(-4625 800);
DISPLAY 0.617021 (-4625 800);
PAINT SKYBLUE (-4625 800);
FORCEPROP 1 LAST PATH I90
J 0
(-5150 1000);
DISPLAY 0.978723 (-5150 1000);
PAINT WHITE (-5150 1000);
DISPLAY INVISIBLE (-5150 1000);
FORCEPROP 0 LAST CDS_SEC 1
J 0
(-5150 950);
PAINT ORANGE (-5150 950);
DISPLAY INVISIBLE (-5150 950);
FORCEPROP 2 LAST CDS_LOCATION R3P2
J 0
(-5150 900);
DISPLAY 0.617021 (-5150 900);
PAINT AQUA (-5150 900);
DISPLAY INVISIBLE (-5150 900);
FORCEPROP 2 LAST SEC 1
J 0
(-5150 1050);
DISPLAY 0.680851 (-5150 1050);
PAINT MONO (-5150 1050);
DISPLAY INVISIBLE (-5150 1050);
FORCEPROP 2 LAST CDS_LIB mstr_discrete
J 0
(-5100 850);
PAINT ORANGE (-5100 850);
DISPLAY INVISIBLE (-5100 850);
FORCEPROP 2 LAST SEC_TYPE 0402
J 0
(-5150 1050);
DISPLAY 1.021277 (-5150 1050);
PAINT ORANGE (-5150 1050);
DISPLAY INVISIBLE (-5150 1050);
FORCEADD RES..1
(-5100 700);
FORCEPROP 1 LAST PACK_TYPE 0402
J 0
(-4900 650);
DISPLAY 0.617021 (-4900 650);
PAINT SKYBLUE (-4900 650);
FORCEPROP 1 LASTPIN (-5000 700) $PN 2
J 0
(-5038 712);
DISPLAY 0.617021 (-5038 712);
PAINT ORANGE (-5038 712);
FORCEPROP 1 LASTPIN (-5200 700) $PN 1
J 0
(-5188 712);
DISPLAY 0.617021 (-5188 712);
PAINT ORANGE (-5188 712);
FORCEPROP 1 LAST VALUE 0.0
J 2
(-5200 700);
DISPLAY 0.617021 (-5200 700);
PAINT SKYBLUE (-5200 700);
FORCEPROP 1 LAST LOCATION R2P1
J 0
(-5150 750);
DISPLAY 0.617021 (-5150 750);
PAINT AQUA (-5150 750);
FORCEPROP 1 LAST TOLERANCE 5%
J 0
(-5125 650);
DISPLAY 0.617021 (-5125 650);
PAINT SKYBLUE (-5125 650);
FORCEPROP 1 LAST PART_NUMBER G21497-005
J 0
(-5350 650);
DISPLAY 0.617021 (-5350 650);
PAINT BLUE (-5350 650);
FORCEPROP 1 LAST MATERIAL CHIP
J 0
(-5025 650);
DISPLAY 0.617021 (-5025 650);
PAINT SKYBLUE (-5025 650);
FORCEPROP 1 LAST WATTAGE 1/16W
J 2
(-4625 650);
DISPLAY 0.617021 (-4625 650);
PAINT SKYBLUE (-4625 650);
FORCEPROP 2 LAST SEC_TYPE 0402
J 0
(-5150 900);
DISPLAY 1.021277 (-5150 900);
PAINT ORANGE (-5150 900);
DISPLAY INVISIBLE (-5150 900);
FORCEPROP 2 LAST CDS_LIB mstr_discrete
J 0
(-5100 700);
PAINT ORANGE (-5100 700);
DISPLAY INVISIBLE (-5100 700);
FORCEPROP 2 LAST SEC 1
J 0
(-5150 900);
DISPLAY 0.680851 (-5150 900);
PAINT MONO (-5150 900);
DISPLAY INVISIBLE (-5150 900);
FORCEPROP 2 LAST CDS_LOCATION R2P1
J 0
(-5400 700);
DISPLAY 0.617021 (-5400 700);
PAINT AQUA (-5400 700);
DISPLAY INVISIBLE (-5400 700);
FORCEPROP 0 LAST CDS_SEC 1
J 0
(-4975 750);
PAINT ORANGE (-4975 750);
DISPLAY INVISIBLE (-4975 750);
FORCEPROP 1 LAST PATH I91
J 0
(-5150 850);
DISPLAY 0.978723 (-5150 850);
PAINT WHITE (-5150 850);
DISPLAY INVISIBLE (-5150 850);
FORCEADD OFFPAGE..2
R 2
(-6050 850);
FORCEPROP 2 LAST $XR1 147 
J 0
(-6455 850);
DISPLAY 0.638298 (-6455 850);
PAINT MONO (-6455 850);
FORCEPROP 2 LAST $XR0 139 
J 0
(-6335 850);
DISPLAY 0.638298 (-6335 850);
PAINT MONO (-6335 850);
FORCEPROP 1 LAST COMMENT_BODY TRUE
J 2
(-6005 755);
DISPLAY 0.872340 (-6005 755);
PAINT GREEN (-6005 755);
DISPLAY INVISIBLE (-6005 755);
FORCEPROP 1 LAST OFFPAGE TRUE
J 2
(-6375 725);
DISPLAY 0.872340 (-6375 725);
PAINT GREEN (-6375 725);
DISPLAY INVISIBLE (-6375 725);
FORCEPROP 2 LAST CDS_LIB mstr_standard
J 0
(-6050 850);
PAINT ORANGE (-6050 850);
DISPLAY INVISIBLE (-6050 850);
FORCEPROP 2 LAST PATH I92
J 0
(-6300 900);
DISPLAY 1.021277 (-6300 900);
PAINT ORANGE (-6300 900);
DISPLAY INVISIBLE (-6300 900);
FORCEADD OFFPAGE..5
(-6050 700);
FORCEPROP 2 LAST $XR1 147 
J 0
(-6455 700);
DISPLAY 0.638298 (-6455 700);
PAINT MONO (-6455 700);
FORCEPROP 2 LAST $XR0 139 
J 0
(-6335 700);
DISPLAY 0.638298 (-6335 700);
PAINT MONO (-6335 700);
FORCEPROP 1 LAST COMMENT_BODY TRUE
J 0
(-5950 625);
DISPLAY 0.872340 (-5950 625);
PAINT GREEN (-5950 625);
DISPLAY INVISIBLE (-5950 625);
FORCEPROP 1 LAST OFFPAGE TRUE
J 0
(-5725 575);
DISPLAY 0.872340 (-5725 575);
PAINT GREEN (-5725 575);
DISPLAY INVISIBLE (-5725 575);
FORCEPROP 2 LAST CDS_LIB mstr_standard
J 0
(-6050 700);
PAINT ORANGE (-6050 700);
DISPLAY INVISIBLE (-6050 700);
FORCEPROP 2 LAST PATH I93
J 0
(-6300 750);
DISPLAY 1.021277 (-6300 750);
PAINT ORANGE (-6300 750);
DISPLAY INVISIBLE (-6300 750);
FORCEADD OFFPAGE..5
(-6050 550);
FORCEPROP 2 LAST $XR1 147 
J 0
(-6455 550);
DISPLAY 0.638298 (-6455 550);
PAINT MONO (-6455 550);
FORCEPROP 2 LAST $XR0 139 
J 0
(-6335 550);
DISPLAY 0.638298 (-6335 550);
PAINT MONO (-6335 550);
FORCEPROP 1 LAST COMMENT_BODY TRUE
J 0
(-5950 475);
DISPLAY 0.872340 (-5950 475);
PAINT GREEN (-5950 475);
DISPLAY INVISIBLE (-5950 475);
FORCEPROP 1 LAST OFFPAGE TRUE
J 0
(-5725 425);
DISPLAY 0.872340 (-5725 425);
PAINT GREEN (-5725 425);
DISPLAY INVISIBLE (-5725 425);
FORCEPROP 2 LAST CDS_LIB mstr_standard
J 0
(-6050 550);
PAINT ORANGE (-6050 550);
DISPLAY INVISIBLE (-6050 550);
FORCEPROP 2 LAST PATH I94
J 0
(-6300 600);
DISPLAY 1.021277 (-6300 600);
PAINT ORANGE (-6300 600);
DISPLAY INVISIBLE (-6300 600);
FORCEADD OFFPAGE..1
(-6600 3500);
FORCEPROP 2 LAST $XR2 150 
J 0
(-7092 3500);
DISPLAY 0.638298 (-7092 3500);
PAINT MONO (-7092 3500);
FORCEPROP 2 LAST $XR1 147 
J 0
(-6972 3500);
DISPLAY 0.638298 (-6972 3500);
PAINT MONO (-6972 3500);
FORCEPROP 2 LAST $XR0 139 
J 0
(-6852 3500);
DISPLAY 0.638298 (-6852 3500);
PAINT MONO (-6852 3500);
FORCEPROP 1 LAST COMMENT_BODY TRUE
J 0
(-6475 3400);
DISPLAY 1.404255 (-6475 3400);
PAINT PEACH (-6475 3400);
DISPLAY INVISIBLE (-6475 3400);
FORCEPROP 1 LAST OFFPAGE TRUE
J 0
(-6275 3375);
PAINT GREEN (-6275 3375);
DISPLAY INVISIBLE (-6275 3375);
FORCEPROP 2 LAST CDS_LIB mstr_standard
J 0
(-6600 3500);
PAINT ORANGE (-6600 3500);
DISPLAY INVISIBLE (-6600 3500);
FORCEPROP 2 LAST PATH I95
J 0
(-6875 3550);
DISPLAY 1.021277 (-6875 3550);
PAINT ORANGE (-6875 3550);
DISPLAY INVISIBLE (-6875 3550);
FORCEADD OFFPAGE..4
R 2
(-6600 3400);
FORCEPROP 2 LAST $XR1 139 
J 0
(-6972 3400);
DISPLAY 0.638298 (-6972 3400);
PAINT MONO (-6972 3400);
FORCEPROP 2 LAST $XR0 147 
J 0
(-6852 3400);
DISPLAY 0.638298 (-6852 3400);
PAINT MONO (-6852 3400);
FORCEPROP 1 LAST COMMENT_BODY TRUE
J 2
(-6575 3300);
DISPLAY 0.872340 (-6575 3300);
PAINT GREEN (-6575 3300);
DISPLAY INVISIBLE (-6575 3300);
FORCEPROP 1 LAST OFFPAGE TRUE
J 2
(-6925 3275);
DISPLAY 0.872340 (-6925 3275);
PAINT GREEN (-6925 3275);
DISPLAY INVISIBLE (-6925 3275);
FORCEPROP 2 LAST CDS_LIB mstr_standard
J 0
(-6600 3400);
PAINT ORANGE (-6600 3400);
DISPLAY INVISIBLE (-6600 3400);
FORCEPROP 2 LAST PATH I96
J 0
(-6875 3450);
DISPLAY 1.021277 (-6875 3450);
PAINT ORANGE (-6875 3450);
DISPLAY INVISIBLE (-6875 3450);
FORCEADD OFFPAGE..4
R 2
(-6600 3450);
FORCEPROP 2 LAST $XR1 139 
J 0
(-6972 3450);
DISPLAY 0.638298 (-6972 3450);
PAINT MONO (-6972 3450);
FORCEPROP 2 LAST $XR0 147 
J 0
(-6852 3450);
DISPLAY 0.638298 (-6852 3450);
PAINT MONO (-6852 3450);
FORCEPROP 1 LAST COMMENT_BODY TRUE
J 2
(-6575 3350);
DISPLAY 0.872340 (-6575 3350);
PAINT GREEN (-6575 3350);
DISPLAY INVISIBLE (-6575 3350);
FORCEPROP 1 LAST OFFPAGE TRUE
J 2
(-6925 3325);
DISPLAY 0.872340 (-6925 3325);
PAINT GREEN (-6925 3325);
DISPLAY INVISIBLE (-6925 3325);
FORCEPROP 2 LAST CDS_LIB mstr_standard
J 2
(-6600 3450);
PAINT ORANGE (-6600 3450);
DISPLAY INVISIBLE (-6600 3450);
FORCEPROP 2 LAST PATH I97
J 0
(-6875 3500);
DISPLAY 1.021277 (-6875 3500);
PAINT ORANGE (-6875 3500);
DISPLAY INVISIBLE (-6875 3500);
FORCEADD RES..1
(-5100 1025);
FORCEPROP 1 LASTPIN (-5000 1025) $PN 2
J 0
(-5038 1037);
DISPLAY 0.617021 (-5038 1037);
PAINT ORANGE (-5038 1037);
FORCEPROP 1 LAST TOLERANCE 1%
J 0
(-5125 975);
DISPLAY 0.617021 (-5125 975);
PAINT SKYBLUE (-5125 975);
FORCEPROP 1 LAST VALUE 33.2
J 2
(-5200 1025);
DISPLAY 0.617021 (-5200 1025);
PAINT SKYBLUE (-5200 1025);
FORCEPROP 1 LASTPIN (-5200 1025) $PN 1
J 0
(-5188 1037);
DISPLAY 0.617021 (-5188 1037);
PAINT ORANGE (-5188 1037);
FORCEPROP 1 LAST PART_NUMBER G21796-074
J 0
(-5350 975);
DISPLAY 0.617021 (-5350 975);
PAINT BLUE (-5350 975);
FORCEPROP 1 LAST PACK_TYPE 0402
J 0
(-4900 975);
DISPLAY 0.617021 (-4900 975);
PAINT SKYBLUE (-4900 975);
FORCEPROP 1 LAST MATERIAL CHIP
J 0
(-5025 975);
DISPLAY 0.617021 (-5025 975);
PAINT SKYBLUE (-5025 975);
FORCEPROP 1 LAST LOCATION R7C14
J 0
(-5150 1075);
DISPLAY 0.617021 (-5150 1075);
PAINT AQUA (-5150 1075);
FORCEPROP 1 LAST WATTAGE 1/16W
J 2
(-4625 975);
DISPLAY 0.617021 (-4625 975);
PAINT SKYBLUE (-4625 975);
FORCEPROP 1 LAST PATH I98
J 0
(-5150 1175);
DISPLAY 0.978723 (-5150 1175);
PAINT WHITE (-5150 1175);
DISPLAY INVISIBLE (-5150 1175);
FORCEPROP 0 LAST CDS_SEC 1
J 0
(-4900 1025);
PAINT ORANGE (-4900 1025);
DISPLAY INVISIBLE (-4900 1025);
FORCEPROP 2 LAST CDS_LOCATION R7C14
J 0
(-4900 975);
DISPLAY 0.617021 (-4900 975);
PAINT AQUA (-4900 975);
DISPLAY INVISIBLE (-4900 975);
FORCEPROP 2 LAST SEC 1
J 0
(-5150 1225);
DISPLAY 0.680851 (-5150 1225);
PAINT MONO (-5150 1225);
DISPLAY INVISIBLE (-5150 1225);
FORCEPROP 2 LAST SEC_TYPE 0402
J 0
(-5150 1225);
DISPLAY 1.021277 (-5150 1225);
PAINT ORANGE (-5150 1225);
DISPLAY INVISIBLE (-5150 1225);
FORCEPROP 2 LAST CDS_LIB mstr_discrete
J 0
(-5100 1025);
PAINT ORANGE (-5100 1025);
DISPLAY INVISIBLE (-5100 1025);
FORCEPROP 0 LAST ROOM SB
J 0
(-5050 1125);
DISPLAY 1.021277 (-5050 1125);
PAINT ORANGE (-5050 1125);
DISPLAY INVISIBLE (-5050 1125);
FORCEADD OFFPAGE..5
(-6050 1025);
FORCEPROP 2 LAST $XR1 147 
J 0
(-6455 1025);
DISPLAY 0.638298 (-6455 1025);
PAINT MONO (-6455 1025);
FORCEPROP 2 LAST $XR0 125 
J 0
(-6335 1025);
DISPLAY 0.638298 (-6335 1025);
PAINT MONO (-6335 1025);
FORCEPROP 1 LAST COMMENT_BODY TRUE
J 0
(-5950 950);
DISPLAY 0.872340 (-5950 950);
PAINT GREEN (-5950 950);
DISPLAY INVISIBLE (-5950 950);
FORCEPROP 1 LAST OFFPAGE TRUE
J 0
(-5725 900);
DISPLAY 0.872340 (-5725 900);
PAINT GREEN (-5725 900);
DISPLAY INVISIBLE (-5725 900);
FORCEPROP 2 LAST CDS_LIB mstr_standard
J 0
(-6050 1025);
PAINT ORANGE (-6050 1025);
DISPLAY INVISIBLE (-6050 1025);
FORCEPROP 2 LAST PATH I99
J 0
(-6325 1075);
DISPLAY 1.021277 (-6325 1075);
PAINT ORANGE (-6325 1075);
DISPLAY INVISIBLE (-6325 1075);
FORCEADD CAD_NOTE..1
(-7550 975);
FORCEPROP 0 LAST L2 RES NEAR PCH
J 0
(-7700 825);
DISPLAY 0.808511 (-7700 825);
PAINT ORANGE (-7700 825);
FORCEPROP 0 LAST L1 PLACE CLK_50M_CKMNG_PCH_10GBE
J 0
(-7700 875);
DISPLAY 0.808511 (-7700 875);
PAINT ORANGE (-7700 875);
FORCEPROP 1 LAST COMMENT_BODY TRUE
J 0
(-7525 1075);
DISPLAY 0.978723 (-7525 1075);
PAINT ORANGE (-7525 1075);
DISPLAY INVISIBLE (-7525 1075);
FORCEPROP 2 LAST CDS_LIB mstr_symbols
J 0
(-7550 975);
PAINT ORANGE (-7550 975);
DISPLAY INVISIBLE (-7550 975);
FORCEADD CAD_NOTE..1
(-2325 4350);
FORCEPROP 0 LAST L1 PLACE SPI SERIES RES CLOSE TO PCH
J 0
(-2475 4225);
DISPLAY 1.021277 (-2475 4225);
PAINT ORANGE (-2475 4225);
FORCEPROP 2 LAST CDS_LIB mstr_symbols
J 0
(-2325 4350);
PAINT ORANGE (-2325 4350);
DISPLAY INVISIBLE (-2325 4350);
FORCEPROP 1 LAST COMMENT_BODY TRUE
J 0
(-2300 4450);
DISPLAY 0.978723 (-2300 4450);
PAINT ORANGE (-2300 4450);
DISPLAY INVISIBLE (-2300 4450);
FORCEADD INTEL_CORP_BPAGE..1
(-450 0);
FORCEPROP 1 LAST CDS_CON_LAST_MODIFIED Fri Jun 16 17:48:47 2017
J 0
(-1875 325);
DISPLAY 1.340426 (-1875 325);
PAINT ORANGE (-1875 325);
DISPLAY INVISIBLE (-1875 325);
FORCEPROP 1 LAST CUSTOM_TXT_CDS <CURRENT_DESIGN_SHEET> OF <TOTAL_DESIGN_SHEETS>
J 0
(-950 25);
PAINT ORANGE (-950 25);
FORCEPROP 1 LAST CUSTOM_TXT_CDS <CON_LAST_MODIFIED>
J 0
(-4450 100);
PAINT ORANGE (-4450 100);
FORCEPROP 2 LAST CUSTOM_TXT_CDS <XR_PAGE_TITLE>
J 0
(-8340 5250);
DISPLAY 0.638298 (-8340 5250);
PAINT PINK (-8340 5250);
DISPLAY INVISIBLE (-8340 5250);
FORCEPROP 1 LAST SCH_TITLE LEWISBURG 8/11 RMII, SPI
J 0
(-8400 50);
DISPLAY 1.212766 (-8400 50);
PAINT GREEN (-8400 50);
FORCEPROP 2 LAST CDS_LIB mstr_symbols
J 0
(-450 0);
PAINT ORANGE (-450 0);
DISPLAY INVISIBLE (-450 0);
FORCEPROP 2 LAST PAGE_BORDER TRUE
J 0
(-8340 5250);
DISPLAY 0.851064 (-8340 5250);
PAINT PINK (-8340 5250);
DISPLAY INVISIBLE (-8340 5250);
FORCEPROP 1 LAST COMMENT_BODY TRUE
J 0
(-438 12);
DISPLAY 0.638298 (-438 12);
PAINT GREEN (-438 12);
DISPLAY INVISIBLE (-438 12);
FORCEPROP 2 LAST CDS_XR_PAGE_TITLE CR-121 : @BASEBOARD_FAB2_LIB.BASEBOARD_FAB2(SCH_1):PAGE121
J 0
(-8340 5250);
DISPLAY 0.638298 (-8340 5250);
PAINT PINK (-8340 5250);
DISPLAY INVISIBLE (-8340 5250);
FORCEADD CAD_NOTE..1
(-7700 4600);
FORCEPROP 0 LAST L6 RMII_SPRNGVLLE_BMC_PCH_RXD1_R1
J 0
(-7850 4250);
DISPLAY 0.808511 (-7850 4250);
PAINT ORANGE (-7850 4250);
FORCEPROP 0 LAST L1 PLACE SERIES RESISTORS ON THE FOLLOWING
J 0
(-7850 4500);
DISPLAY 0.808511 (-7850 4500);
PAINT ORANGE (-7850 4500);
FORCEPROP 0 LAST L3 RMII_PCH_SPRNGVLLE_ARB_OUT_R
J 0
(-7850 4400);
DISPLAY 0.808511 (-7850 4400);
PAINT ORANGE (-7850 4400);
FORCEPROP 0 LAST L4 RMII_BMC_PCH_SPRNGVLLE_RXER_R
J 0
(-7850 4350);
DISPLAY 0.808511 (-7850 4350);
PAINT ORANGE (-7850 4350);
FORCEPROP 0 LAST L5 RMII_BMC_PCH_SRNGVLLE_CRSDV_R1
J 0
(-7850 4300);
DISPLAY 0.808511 (-7850 4300);
PAINT ORANGE (-7850 4300);
FORCEPROP 0 LAST L2 NETS WITHIN TWO INCHES OF THE PCH:
J 0
(-7850 4450);
DISPLAY 0.808511 (-7850 4450);
PAINT ORANGE (-7850 4450);
FORCEPROP 0 LAST L7 RMII_SPRNGVLLE_BMC_PCH_RXD0_R1
J 0
(-7850 4200);
DISPLAY 0.808511 (-7850 4200);
PAINT ORANGE (-7850 4200);
FORCEPROP 2 LAST CDS_LIB mstr_symbols
J 0
(-7700 4600);
PAINT ORANGE (-7700 4600);
DISPLAY INVISIBLE (-7700 4600);
FORCEPROP 1 LAST COMMENT_BODY TRUE
J 0
(-7675 4700);
DISPLAY 0.978723 (-7675 4700);
PAINT ORANGE (-7675 4700);
DISPLAY INVISIBLE (-7675 4700);
WIRE 16 -1 (-7750 3575)(-7750 3500);
WIRE 16 -1 (-8075 2700)(-8075 2625);
WIRE 16 -1 (-8125 850)(-8125 725);
WIRE 16 -1 (-2700 2150)(-1425 2150);
FORCEPROP 2 LAST SIG_NAME FM_SINT_PRSNT_N
J 2
(-1435 2160);
DISPLAY 0.617021 (-1435 2160);
PAINT ORANGE (-1435 2160);
WIRE 16 -1 (-2700 2500)(-1425 2500);
WIRE 16 -1 (-6550 2900)(-5400 2900);
FORCEPROP 2 LAST SIG_NAME H_CPU0_MEMABC_MEMHOT_PCH_N
J 0
(-6500 2910);
DISPLAY 0.617021 (-6500 2910);
PAINT ORANGE (-6500 2910);
WIRE 16 -1 (-3050 675)(-3050 575);
WIRE 16 -1 (-3050 575)(-2325 575);
WIRE 16 -1 (-3050 675)(-675 675);
WIRE 16 -1 (-3050 775)(-3050 675);
WIRE 16 -1 (-3050 775)(-675 775);
WIRE 16 -1 (-675 675)(-675 775);
WIRE 16 -1 (-3050 875)(-3050 775);
WIRE 16 -1 (-675 675)(-675 575);
WIRE 16 -1 (-2325 575)(-1850 575);
WIRE 16 -1 (-2325 1175)(-2325 575);
WIRE 16 -1 (-1850 1175)(-2325 1175);
WIRE 16 -1 (-1850 1175)(-1850 575);
WIRE 16 -1 (-1350 575)(-1850 575);
WIRE 16 -1 (-675 575)(-1350 575);
WIRE 16 -1 (-2325 1175)(-3050 1175);
WIRE 16 -1 (-3050 875)(-675 875);
WIRE 16 -1 (-675 775)(-675 875);
WIRE 16 -1 (-3050 975)(-3050 875);
WIRE 16 -1 (-3050 975)(-675 975);
WIRE 16 -1 (-675 875)(-675 975);
WIRE 16 -1 (-3050 1075)(-3050 975);
WIRE 16 -1 (-3050 1175)(-3050 1075);
WIRE 16 -1 (-1350 1175)(-1350 575);
WIRE 16 -1 (-1350 1175)(-1850 1175);
WIRE 16 -1 (-675 1175)(-1350 1175);
WIRE 16 -1 (-3050 1075)(-675 1075);
WIRE 16 -1 (-675 975)(-675 1075);
WIRE 16 -1 (-675 1075)(-675 1175);
WIRE 16 -1 (-6550 3250)(-5400 3250);
FORCEPROP 2 LAST SIG_NAME FM_CPU_ERR1_PCH_N
J 0
(-6500 3260);
DISPLAY 0.617021 (-6500 3260);
PAINT ORANGE (-6500 3260);
WIRE 16 -1 (-5400 3400)(-6550 3400);
FORCEPROP 2 LAST SIG_NAME RMII_BMC_PCH_SPRNGVLLE_TXD0
J 0
(-6500 3410);
DISPLAY 0.617021 (-6500 3410);
PAINT ORANGE (-6500 3410);
WIRE 16 -1 (-1425 3400)(-2700 3400);
FORCEPROP 0 LAST SIG_NAME SPI_PCH_TPM_CS_N
J 0
(-1785 3410);
DISPLAY 0.617021 (-1785 3410);
PAINT ORANGE (-1785 3410);
WIRE 16 -1 (-5000 550)(-4175 550);
FORCEPROP 2 LAST SIG_NAME RMII_SPRNGVLLE_BMC_PCH_RXD0_R1
J 0
(-4900 560);
DISPLAY 0.617021 (-4900 560);
PAINT ORANGE (-4900 560);
WIRE 16 -1 (-5000 700)(-4175 700);
FORCEPROP 2 LAST SIG_NAME RMII_SPRNGVLLE_BMC_PCH_RXD1_R1
J 0
(-4900 710);
DISPLAY 0.617021 (-4900 710);
PAINT ORANGE (-4900 710);
WIRE 16 -1 (-5000 850)(-4175 850);
FORCEPROP 2 LAST SIG_NAME RMII_BMC_PCH_SPRNGVLLE_CRSDV_R1
J 0
(-4900 860);
DISPLAY 0.617021 (-4900 860);
PAINT ORANGE (-4900 860);
WIRE 16 -1 (-5000 1175)(-4175 1175);
FORCEPROP 2 LAST SIG_NAME RMII_PCH_SPRNGVLLE_ARB_OUT_R
J 0
(-4900 1185);
DISPLAY 0.617021 (-4900 1185);
PAINT ORANGE (-4900 1185);
WIRE 16 -1 (-5000 1025)(-4175 1025);
FORCEPROP 2 LAST SIG_NAME RMII_BMC_PCH_SPRNGVLLE_RXER_R
J 0
(-4900 1035);
DISPLAY 0.617021 (-4900 1035);
PAINT ORANGE (-4900 1035);
WIRE 16 -1 (-6000 1025)(-5200 1025);
FORCEPROP 2 LAST SIG_NAME RMII_BMC_PCH_SPRNGVLLE_RXER
J 0
(-5975 1035);
DISPLAY 0.617021 (-5975 1035);
PAINT ORANGE (-5975 1035);
WIRE 16 -1 (-6000 1175)(-5200 1175);
FORCEPROP 2 LAST SIG_NAME RMII_PCH_SPRNGVLLE_ARB_OUT
J 0
(-5975 1185);
DISPLAY 0.617021 (-5975 1185);
PAINT ORANGE (-5975 1185);
WIRE 16 -1 (-5200 850)(-6000 850);
FORCEPROP 2 LAST SIG_NAME RMII_BMC_PCH_SPRNGVLLE_CRSDV
J 0
(-5975 860);
DISPLAY 0.617021 (-5975 860);
PAINT ORANGE (-5975 860);
WIRE 16 -1 (-5200 700)(-6000 700);
FORCEPROP 2 LAST SIG_NAME RMII_SPRNGVLLE_BMC_PCH_RXD1
J 0
(-5975 710);
DISPLAY 0.617021 (-5975 710);
PAINT ORANGE (-5975 710);
WIRE 16 -1 (-5200 550)(-6000 550);
FORCEPROP 2 LAST SIG_NAME RMII_SPRNGVLLE_BMC_PCH_RXD0
J 0
(-5975 560);
DISPLAY 0.617021 (-5975 560);
PAINT ORANGE (-5975 560);
WIRE 16 -1 (-8075 2300)(-8075 2425);
WIRE 16 -1 (-5400 2300)(-8075 2300);
FORCEPROP 0 LAST SIG_NAME FM_INTRUDER_HDR_PCH_N
J 0
(-7300 2310);
DISPLAY 0.617021 (-7300 2310);
PAINT ORANGE (-7300 2310);
FORCEPROP 2 LASTPROP $XRERR UNIQUE?
J 0
(-7540 2310);
DISPLAY 0.638298 (-7540 2310);
PAINT MONO (-7540 2310);
DISPLAY INVISIBLE (-7540 2310);
WIRE 3 682 (-7100 2400)(-7200 2400);
WIRE 16 -1 (-5400 2750)(-6550 2750);
FORCEPROP 2 LAST SIG_NAME FM_OCP_MEZZC_PRES_1V05_PCH_N
J 0
(-6500 2760);
DISPLAY 0.617021 (-6500 2760);
PAINT ORANGE (-6500 2760);
WIRE 16 -1 (-5400 2700)(-6550 2700);
FORCEPROP 2 LAST SIG_NAME FM_OCP_MEZZB_PRES_1V05_PCH_N
J 0
(-6500 2710);
DISPLAY 0.617021 (-6500 2710);
PAINT ORANGE (-6500 2710);
WIRE 16 -1 (-2100 2800)(-2700 2800);
FORCEPROP 2 LAST SIG_NAME TP_PCH_HDA_SDI_1
J 0
(-2465 2810);
DISPLAY 0.617021 (-2465 2810);
PAINT ORANGE (-2465 2810);
FORCEPROP 2 LASTPROP $XRERR UNIQUE?
J 0
(-2070 2800);
DISPLAY 0.638298 (-2070 2800);
PAINT MONO (-2070 2800);
DISPLAY INVISIBLE (-2070 2800);
WIRE 16 -1 (-2700 2850)(-1425 2850);
FORCEPROP 2 LAST SIG_NAME FM_FLASH_DESC_OVERRIDE
J 2
(-1435 2860);
DISPLAY 0.617021 (-1435 2860);
PAINT ORANGE (-1435 2860);
WIRE 16 -1 (-1425 3200)(-2700 3200);
FORCEPROP 0 LAST SIG_NAME SPI_PCH_MISO
J 2
(-1425 3210);
DISPLAY 0.617021 (-1425 3210);
PAINT ORANGE (-1425 3210);
WIRE 16 -1 (-2700 3250)(-1425 3250);
FORCEPROP 0 LAST SIG_NAME SPI_PCH_IO2
J 2
(-1425 3260);
DISPLAY 0.617021 (-1425 3260);
PAINT ORANGE (-1425 3260);
WIRE 16 -1 (-2700 3300)(-1425 3300);
FORCEPROP 0 LAST SIG_NAME SPI_PCH_IO3
J 2
(-1425 3310);
DISPLAY 0.617021 (-1425 3310);
PAINT ORANGE (-1425 3310);
WIRE 16 -1 (-1425 3450)(-2700 3450);
FORCEPROP 2 LAST SIG_NAME SPI_PCH_CLK
J 2
(-1425 3460);
DISPLAY 0.617021 (-1425 3460);
PAINT ORANGE (-1425 3460);
WIRE 16 -1 (-2050 3550)(-2700 3550);
FORCEPROP 2 LAST SIG_NAME SPI_PCH_CS0_R_N
J 0
(-2465 3560);
DISPLAY 0.617021 (-2465 3560);
PAINT ORANGE (-2465 3560);
FORCEPROP 2 LASTPROP $XRERR UNIQUE?
J 0
(-2705 3560);
DISPLAY 0.638298 (-2705 3560);
PAINT MONO (-2705 3560);
DISPLAY INVISIBLE (-2705 3560);
WIRE 16 -1 (-2025 3150)(-2700 3150);
FORCEPROP 2 LAST SIG_NAME SPI_PCH_MOSI_R
J 0
(-2465 3160);
DISPLAY 0.617021 (-2465 3160);
PAINT ORANGE (-2465 3160);
FORCEPROP 2 LASTPROP $XRERR UNIQUE?
J 0
(-2705 3160);
DISPLAY 0.638298 (-2705 3160);
PAINT MONO (-2705 3160);
DISPLAY INVISIBLE (-2705 3160);
WIRE 16 -1 (-2700 3700)(-1425 3700);
WIRE 16 -1 (-2700 3050)(-2100 3050);
FORCEPROP 2 LAST SIG_NAME TP_PCH_DISPA_SDO
J 0
(-2465 3060);
DISPLAY 0.617021 (-2465 3060);
PAINT ORANGE (-2465 3060);
FORCEPROP 2 LASTPROP $XRERR UNIQUE?
J 0
(-2070 3050);
DISPLAY 0.638298 (-2070 3050);
PAINT MONO (-2070 3050);
DISPLAY INVISIBLE (-2070 3050);
WIRE 16 -1 (-2700 3000)(-2100 3000);
FORCEPROP 2 LAST SIG_NAME TP_PCH_DISPA_SDI
J 0
(-2465 3010);
DISPLAY 0.617021 (-2465 3010);
PAINT ORANGE (-2465 3010);
FORCEPROP 2 LASTPROP $XRERR UNIQUE?
J 0
(-2070 3000);
DISPLAY 0.638298 (-2070 3000);
PAINT MONO (-2070 3000);
DISPLAY INVISIBLE (-2070 3000);
WIRE 16 -1 (-2100 2950)(-2700 2950);
FORCEPROP 2 LAST SIG_NAME TP_PCH_DISPA_BCLK
J 0
(-2465 2960);
DISPLAY 0.617021 (-2465 2960);
PAINT ORANGE (-2465 2960);
FORCEPROP 2 LASTPROP $XRERR UNIQUE?
J 0
(-2070 2950);
DISPLAY 0.638298 (-2070 2950);
PAINT MONO (-2070 2950);
DISPLAY INVISIBLE (-2070 2950);
WIRE 16 -1 (-2700 2900)(-2100 2900);
FORCEPROP 2 LAST SIG_NAME TP_PCH_HDA_SYNC
J 0
(-2465 2910);
DISPLAY 0.617021 (-2465 2910);
PAINT ORANGE (-2465 2910);
FORCEPROP 2 LASTPROP $XRERR UNIQUE?
J 0
(-2070 2900);
DISPLAY 0.638298 (-2070 2900);
PAINT MONO (-2070 2900);
DISPLAY INVISIBLE (-2070 2900);
WIRE 16 -1 (-2700 2700)(-2100 2700);
FORCEPROP 2 LAST SIG_NAME TP_PCH_HSA_RST_N
J 0
(-2465 2710);
DISPLAY 0.617021 (-2465 2710);
PAINT ORANGE (-2465 2710);
FORCEPROP 2 LASTPROP $XRERR UNIQUE?
J 0
(-2070 2700);
DISPLAY 0.638298 (-2070 2700);
PAINT MONO (-2070 2700);
DISPLAY INVISIBLE (-2070 2700);
WIRE 16 -1 (-2100 2650)(-2700 2650);
FORCEPROP 2 LAST SIG_NAME TP_PCH_HDA_BCLK
J 0
(-2465 2660);
DISPLAY 0.617021 (-2465 2660);
PAINT ORANGE (-2465 2660);
FORCEPROP 2 LASTPROP $XRERR UNIQUE?
J 0
(-2070 2650);
DISPLAY 0.638298 (-2070 2650);
PAINT MONO (-2070 2650);
DISPLAY INVISIBLE (-2070 2650);
WIRE 16 -1 (-2700 2550)(-1425 2550);
WIRE 16 -1 (-2700 2050)(-2100 2050);
FORCEPROP 2 LAST SIG_NAME TP_PCH_RSVD9
J 0
(-2465 2060);
DISPLAY 0.617021 (-2465 2060);
PAINT ORANGE (-2465 2060);
FORCEPROP 2 LASTPROP $XRERR UNIQUE?
J 0
(-2070 2050);
DISPLAY 0.638298 (-2070 2050);
PAINT MONO (-2070 2050);
DISPLAY INVISIBLE (-2070 2050);
WIRE 16 -1 (-6550 2650)(-5400 2650);
FORCEPROP 2 LAST SIG_NAME FM_PRSNT_2_6_N
J 0
(-6500 2660);
DISPLAY 0.617021 (-6500 2660);
PAINT ORANGE (-6500 2660);
WIRE 16 -1 (-6550 2600)(-5400 2600);
FORCEPROP 2 LAST SIG_NAME FM_PRSNT_2_5_N
J 0
(-6500 2610);
DISPLAY 0.617021 (-6500 2610);
PAINT ORANGE (-6500 2610);
WIRE 16 -1 (-6550 2550)(-5400 2550);
FORCEPROP 2 LAST SIG_NAME FM_PRSNT_2_4_N
J 0
(-6500 2560);
DISPLAY 0.617021 (-6500 2560);
PAINT ORANGE (-6500 2560);
WIRE 16 -1 (-6550 2500)(-5400 2500);
FORCEPROP 2 LAST SIG_NAME FM_PRSNT_2_3_N
J 0
(-6500 2510);
DISPLAY 0.617021 (-6500 2510);
PAINT ORANGE (-6500 2510);
WIRE 16 -1 (-6550 2450)(-5400 2450);
FORCEPROP 2 LAST SIG_NAME FM_PRSNT_2_2_N
J 0
(-6500 2460);
DISPLAY 0.617021 (-6500 2460);
PAINT ORANGE (-6500 2460);
WIRE 16 -1 (-6550 2400)(-5400 2400);
FORCEPROP 2 LAST SIG_NAME FM_PRSNT_2_1_N
J 0
(-6500 2410);
DISPLAY 0.617021 (-6500 2410);
PAINT ORANGE (-6500 2410);
WIRE 16 -1 (-6550 3200)(-5400 3200);
FORCEPROP 2 LAST SIG_NAME FM_CPU_ERR0_PCH_N
J 0
(-6500 3210);
DISPLAY 0.617021 (-6500 3210);
PAINT ORANGE (-6500 3210);
WIRE 16 -1 (-6550 3050)(-5400 3050);
FORCEPROP 2 LAST SIG_NAME H_CPU1_MEMKLM_MEMHOT_PCH_N
J 0
(-6500 3060);
DISPLAY 0.617021 (-6500 3060);
PAINT ORANGE (-6500 3060);
WIRE 16 -1 (-6550 3100)(-5400 3100);
FORCEPROP 0 LAST SIG_NAME FM_CPU0_PROCHOT_PCH_N
J 0
(-6500 3110);
DISPLAY 0.617021 (-6500 3110);
PAINT ORANGE (-6500 3110);
WIRE 16 -1 (-6550 3150)(-5400 3150);
FORCEPROP 0 LAST SIG_NAME FM_CPU1_PROCHOT_PCH_N
J 0
(-6500 3160);
DISPLAY 0.617021 (-6500 3160);
PAINT ORANGE (-6500 3160);
WIRE 16 -1 (-6550 3000)(-5400 3000);
FORCEPROP 2 LAST SIG_NAME H_CPU1_MEMGHJ_MEMHOT_PCH_N
J 0
(-6500 3010);
DISPLAY 0.617021 (-6500 3010);
PAINT ORANGE (-6500 3010);
WIRE 16 -1 (-6550 2950)(-5400 2950);
FORCEPROP 2 LAST SIG_NAME H_CPU0_MEMDEF_MEMHOT_PCH_N
J 0
(-6500 2960);
DISPLAY 0.617021 (-6500 2960);
PAINT ORANGE (-6500 2960);
WIRE 16 -1 (-5400 2200)(-6000 2200);
FORCEPROP 2 LAST SIG_NAME TP_PCH_RSVD25
J 2
(-5645 2210);
DISPLAY 0.617021 (-5645 2210);
PAINT ORANGE (-5645 2210);
FORCEPROP 2 LASTPROP $XRERR UNIQUE?
J 0
(-6240 2200);
DISPLAY 0.638298 (-6240 2200);
PAINT MONO (-6240 2200);
DISPLAY INVISIBLE (-6240 2200);
WIRE 16 -1 (-5400 2850)(-6000 2850);
FORCEPROP 2 LAST SIG_NAME TP_PCH_GPP_L11
J 0
(-5935 2860);
DISPLAY 0.617021 (-5935 2860);
PAINT ORANGE (-5935 2860);
FORCEPROP 2 LASTPROP $XRERR UNIQUE?
J 0
(-6240 2850);
DISPLAY 0.638298 (-6240 2850);
PAINT MONO (-6240 2850);
DISPLAY INVISIBLE (-6240 2850);
WIRE 16 -1 (-5400 2800)(-6000 2800);
FORCEPROP 2 LAST SIG_NAME TP_PCH_GPP_L10
J 0
(-5935 2810);
DISPLAY 0.617021 (-5935 2810);
PAINT ORANGE (-5935 2810);
FORCEPROP 2 LASTPROP $XRERR UNIQUE?
J 0
(-6240 2800);
DISPLAY 0.638298 (-6240 2800);
PAINT MONO (-6240 2800);
DISPLAY INVISIBLE (-6240 2800);
WIRE 2 -1 (-7200 2700)(-7100 2700);
WIRE 2 -1 (-7200 2750)(-7200 2700);
WIRE 2 -1 (-7100 2750)(-7200 2750);
WIRE 2 -1 (-7200 2800)(-7200 2750);
WIRE 16 -1 (-5400 2150)(-6000 2150);
FORCEPROP 2 LAST SIG_NAME TP_PCH_RSVD24
J 2
(-5645 2160);
DISPLAY 0.617021 (-5645 2160);
PAINT ORANGE (-5645 2160);
FORCEPROP 2 LASTPROP $XRERR UNIQUE?
J 0
(-6240 2150);
DISPLAY 0.638298 (-6240 2150);
PAINT MONO (-6240 2150);
DISPLAY INVISIBLE (-6240 2150);
WIRE 16 -1 (-6550 3650)(-5400 3650);
FORCEPROP 2 LAST SIG_NAME RMII_SPRNGVLLE_BMC_PCH_RXD1_R1
J 0
(-6500 3660);
DISPLAY 0.617021 (-6500 3660);
PAINT ORANGE (-6500 3660);
WIRE 16 -1 (-6550 3600)(-5400 3600);
FORCEPROP 2 LAST SIG_NAME RMII_SPRNGVLLE_BMC_PCH_RXD0_R1
J 0
(-6500 3610);
DISPLAY 0.617021 (-6500 3610);
PAINT ORANGE (-6500 3610);
WIRE 16 -1 (-5400 3450)(-6550 3450);
FORCEPROP 2 LAST SIG_NAME RMII_BMC_PCH_SPRNGVLLE_TXD1
J 0
(-6500 3460);
DISPLAY 0.617021 (-6500 3460);
PAINT ORANGE (-6500 3460);
WIRE 16 -1 (-6550 3350)(-5400 3350);
FORCEPROP 2 LAST SIG_NAME CLK_50M_CKMNG_PCH_10GBE
J 0
(-6500 3360);
DISPLAY 0.617021 (-6500 3360);
PAINT ORANGE (-6500 3360);
WIRE 16 -1 (-5400 3500)(-6550 3500);
FORCEPROP 2 LAST SIG_NAME RMII_BMC_PCH_SPRNGVLLE_TXEN
J 0
(-6500 3510);
DISPLAY 0.617021 (-6500 3510);
PAINT ORANGE (-6500 3510);
WIRE 16 -1 (-6550 3550)(-5400 3550);
FORCEPROP 2 LAST SIG_NAME RMII_BMC_PCH_SPRNGVLLE_CRSDV_R1
J 0
(-6500 3560);
DISPLAY 0.617021 (-6500 3560);
PAINT ORANGE (-6500 3560);
WIRE 16 -1 (-7750 3900)(-7750 3775);
WIRE 16 -1 (-7750 3900)(-5400 3900);
FORCEPROP 0 LAST SIG_NAME A_1P8_3P3_RCOMP
J 0
(-6500 3910);
DISPLAY 0.617021 (-6500 3910);
PAINT ORANGE (-6500 3910);
FORCEPROP 2 LASTPROP $XRERR UNIQUE?
J 0
(-6740 3910);
DISPLAY 0.638298 (-6740 3910);
PAINT MONO (-6740 3910);
DISPLAY INVISIBLE (-6740 3910);
WIRE 16 -1 (-8125 1175)(-8125 1050);
WIRE 16 -1 (-8125 1175)(-7375 1175);
FORCEPROP 0 LAST SIG_NAME CLK_50M_CKMNG_PCH_10GBE
J 0
(-7960 1185);
DISPLAY 0.617021 (-7960 1185);
PAINT ORANGE (-7960 1185);
WIRE 16 -1 (-5400 3700)(-6550 3700);
FORCEPROP 2 LAST SIG_NAME RMII_BMC_PCH_SPRNGVLLE_RXER_R
J 0
(-6500 3710);
DISPLAY 0.617021 (-6500 3710);
PAINT ORANGE (-6500 3710);
WIRE 16 -1 (-6550 3750)(-5400 3750);
FORCEPROP 2 LAST SIG_NAME RMII_PCH_SPRNGVLLE_ARB_IN
J 0
(-6500 3760);
DISPLAY 0.617021 (-6500 3760);
PAINT ORANGE (-6500 3760);
WIRE 16 -1 (-5400 3800)(-6550 3800);
FORCEPROP 2 LAST SIG_NAME RMII_PCH_SPRNGVLLE_ARB_OUT_R
J 0
(-6500 3810);
DISPLAY 0.617021 (-6500 3810);
PAINT ORANGE (-6500 3810);
WIRE 16 -1 (-6000 1750)(-5400 1750);
FORCEPROP 2 LAST SIG_NAME TP_PCH_RSVD16
J 2
(-5645 1760);
DISPLAY 0.617021 (-5645 1760);
PAINT ORANGE (-5645 1760);
FORCEPROP 2 LASTPROP $XRERR UNIQUE?
J 0
(-6240 1750);
DISPLAY 0.638298 (-6240 1750);
PAINT MONO (-6240 1750);
DISPLAY INVISIBLE (-6240 1750);
WIRE 16 -1 (-5400 3850)(-6550 3850);
FORCEPROP 2 LAST SIG_NAME RST_PCIE_PCH_PERST_N
J 0
(-6500 3860);
DISPLAY 0.617021 (-6500 3860);
PAINT ORANGE (-6500 3860);
WIRE 16 -1 (-6000 1650)(-5400 1650);
FORCEPROP 2 LAST SIG_NAME TP_PCH_RSVD14
J 2
(-5645 1660);
DISPLAY 0.617021 (-5645 1660);
PAINT ORANGE (-5645 1660);
FORCEPROP 2 LASTPROP $XRERR UNIQUE?
J 0
(-6240 1650);
DISPLAY 0.638298 (-6240 1650);
PAINT MONO (-6240 1650);
DISPLAY INVISIBLE (-6240 1650);
WIRE 16 -1 (-6000 1600)(-5400 1600);
FORCEPROP 2 LAST SIG_NAME TP_PCH_RSVD13
J 2
(-5645 1610);
DISPLAY 0.617021 (-5645 1610);
PAINT ORANGE (-5645 1610);
FORCEPROP 2 LASTPROP $XRERR UNIQUE?
J 0
(-6240 1600);
DISPLAY 0.638298 (-6240 1600);
PAINT MONO (-6240 1600);
DISPLAY INVISIBLE (-6240 1600);
WIRE 16 -1 (-2100 1800)(-2700 1800);
FORCEPROP 2 LAST SIG_NAME TP_PCH_RSVD4
J 0
(-2465 1810);
DISPLAY 0.617021 (-2465 1810);
PAINT ORANGE (-2465 1810);
FORCEPROP 2 LASTPROP $XRERR UNIQUE?
J 0
(-2070 1800);
DISPLAY 0.638298 (-2070 1800);
PAINT MONO (-2070 1800);
DISPLAY INVISIBLE (-2070 1800);
WIRE 16 -1 (-6000 1700)(-5400 1700);
FORCEPROP 2 LAST SIG_NAME TP_PCH_RSVD15
J 2
(-5645 1710);
DISPLAY 0.617021 (-5645 1710);
PAINT ORANGE (-5645 1710);
FORCEPROP 2 LASTPROP $XRERR UNIQUE?
J 0
(-6240 1700);
DISPLAY 0.638298 (-6240 1700);
PAINT MONO (-6240 1700);
DISPLAY INVISIBLE (-6240 1700);
WIRE 16 -1 (-6000 1800)(-5400 1800);
FORCEPROP 2 LAST SIG_NAME TP_PCH_RSVD17
J 2
(-5645 1810);
DISPLAY 0.617021 (-5645 1810);
PAINT ORANGE (-5645 1810);
FORCEPROP 2 LASTPROP $XRERR UNIQUE?
J 0
(-6240 1800);
DISPLAY 0.638298 (-6240 1800);
PAINT MONO (-6240 1800);
DISPLAY INVISIBLE (-6240 1800);
WIRE 16 -1 (-6000 1850)(-5400 1850);
FORCEPROP 2 LAST SIG_NAME TP_PCH_RSVD18
J 2
(-5645 1860);
DISPLAY 0.617021 (-5645 1860);
PAINT ORANGE (-5645 1860);
FORCEPROP 2 LASTPROP $XRERR UNIQUE?
J 0
(-6240 1850);
DISPLAY 0.638298 (-6240 1850);
PAINT MONO (-6240 1850);
DISPLAY INVISIBLE (-6240 1850);
WIRE 16 -1 (-6000 1900)(-5400 1900);
FORCEPROP 2 LAST SIG_NAME TP_PCH_RSVD19
J 2
(-5645 1910);
DISPLAY 0.617021 (-5645 1910);
PAINT ORANGE (-5645 1910);
FORCEPROP 2 LASTPROP $XRERR UNIQUE?
J 0
(-6240 1900);
DISPLAY 0.638298 (-6240 1900);
PAINT MONO (-6240 1900);
DISPLAY INVISIBLE (-6240 1900);
WIRE 16 -1 (-5400 2050)(-6000 2050);
FORCEPROP 2 LAST SIG_NAME TP_PCH_RSVD22
J 2
(-5645 2060);
DISPLAY 0.617021 (-5645 2060);
PAINT ORANGE (-5645 2060);
FORCEPROP 2 LASTPROP $XRERR UNIQUE?
J 0
(-6240 2050);
DISPLAY 0.638298 (-6240 2050);
PAINT MONO (-6240 2050);
DISPLAY INVISIBLE (-6240 2050);
WIRE 16 -1 (-6000 1950)(-5400 1950);
FORCEPROP 2 LAST SIG_NAME TP_PCH_RSVD20
J 2
(-5645 1960);
DISPLAY 0.617021 (-5645 1960);
PAINT ORANGE (-5645 1960);
FORCEPROP 2 LASTPROP $XRERR UNIQUE?
J 0
(-6240 1950);
DISPLAY 0.638298 (-6240 1950);
PAINT MONO (-6240 1950);
DISPLAY INVISIBLE (-6240 1950);
WIRE 16 -1 (-5400 2000)(-6000 2000);
FORCEPROP 2 LAST SIG_NAME TP_PCH_RSVD21
J 2
(-5645 2010);
DISPLAY 0.617021 (-5645 2010);
PAINT ORANGE (-5645 2010);
FORCEPROP 2 LASTPROP $XRERR UNIQUE?
J 0
(-6240 2000);
DISPLAY 0.638298 (-6240 2000);
PAINT MONO (-6240 2000);
DISPLAY INVISIBLE (-6240 2000);
WIRE 16 -1 (-5400 2100)(-6000 2100);
FORCEPROP 2 LAST SIG_NAME TP_PCH_RSVD23
J 2
(-5645 2110);
DISPLAY 0.617021 (-5645 2110);
PAINT ORANGE (-5645 2110);
FORCEPROP 2 LASTPROP $XRERR UNIQUE?
J 0
(-6240 2100);
DISPLAY 0.638298 (-6240 2100);
PAINT MONO (-6240 2100);
DISPLAY INVISIBLE (-6240 2100);
WIRE 16 -1 (-2100 1600)(-2700 1600);
FORCEPROP 2 LAST SIG_NAME TP_PCH_RSVD0
J 0
(-2465 1610);
DISPLAY 0.617021 (-2465 1610);
PAINT ORANGE (-2465 1610);
FORCEPROP 2 LASTPROP $XRERR UNIQUE?
J 0
(-2070 1600);
DISPLAY 0.638298 (-2070 1600);
PAINT MONO (-2070 1600);
DISPLAY INVISIBLE (-2070 1600);
WIRE 16 -1 (-2100 1650)(-2700 1650);
FORCEPROP 2 LAST SIG_NAME TP_PCH_RSVD1
J 0
(-2465 1660);
DISPLAY 0.617021 (-2465 1660);
PAINT ORANGE (-2465 1660);
FORCEPROP 2 LASTPROP $XRERR UNIQUE?
J 0
(-2070 1650);
DISPLAY 0.638298 (-2070 1650);
PAINT MONO (-2070 1650);
DISPLAY INVISIBLE (-2070 1650);
WIRE 16 -1 (-2100 1700)(-2700 1700);
FORCEPROP 2 LAST SIG_NAME TP_PCH_RSVD2
J 0
(-2465 1710);
DISPLAY 0.617021 (-2465 1710);
PAINT ORANGE (-2465 1710);
FORCEPROP 2 LASTPROP $XRERR UNIQUE?
J 0
(-2070 1700);
DISPLAY 0.638298 (-2070 1700);
PAINT MONO (-2070 1700);
DISPLAY INVISIBLE (-2070 1700);
WIRE 16 -1 (-2100 1750)(-2700 1750);
FORCEPROP 2 LAST SIG_NAME TP_PCH_RSVD3
J 0
(-2465 1760);
DISPLAY 0.617021 (-2465 1760);
PAINT ORANGE (-2465 1760);
FORCEPROP 2 LASTPROP $XRERR UNIQUE?
J 0
(-2070 1750);
DISPLAY 0.638298 (-2070 1750);
PAINT MONO (-2070 1750);
DISPLAY INVISIBLE (-2070 1750);
WIRE 16 -1 (-2100 1850)(-2700 1850);
FORCEPROP 2 LAST SIG_NAME TP_PCH_RSVD5
J 0
(-2465 1860);
DISPLAY 0.617021 (-2465 1860);
PAINT ORANGE (-2465 1860);
FORCEPROP 2 LASTPROP $XRERR UNIQUE?
J 0
(-2070 1850);
DISPLAY 0.638298 (-2070 1850);
PAINT MONO (-2070 1850);
DISPLAY INVISIBLE (-2070 1850);
WIRE 16 -1 (-2100 1900)(-2700 1900);
FORCEPROP 2 LAST SIG_NAME TP_PCH_RSVD6
J 0
(-2465 1910);
DISPLAY 0.617021 (-2465 1910);
PAINT ORANGE (-2465 1910);
FORCEPROP 2 LASTPROP $XRERR UNIQUE?
J 0
(-2070 1900);
DISPLAY 0.638298 (-2070 1900);
PAINT MONO (-2070 1900);
DISPLAY INVISIBLE (-2070 1900);
WIRE 16 -1 (-2100 1950)(-2700 1950);
FORCEPROP 2 LAST SIG_NAME TP_PCH_RSVD7
J 0
(-2465 1960);
DISPLAY 0.617021 (-2465 1960);
PAINT ORANGE (-2465 1960);
FORCEPROP 2 LASTPROP $XRERR UNIQUE?
J 0
(-2070 1950);
DISPLAY 0.638298 (-2070 1950);
PAINT MONO (-2070 1950);
DISPLAY INVISIBLE (-2070 1950);
WIRE 16 -1 (-2700 2000)(-2100 2000);
FORCEPROP 2 LAST SIG_NAME TP_PCH_RSVD8
J 0
(-2465 2010);
DISPLAY 0.617021 (-2465 2010);
PAINT ORANGE (-2465 2010);
FORCEPROP 2 LASTPROP $XRERR UNIQUE?
J 0
(-2070 2000);
DISPLAY 0.638298 (-2070 2000);
PAINT MONO (-2070 2000);
DISPLAY INVISIBLE (-2070 2000);
WIRE 16 -1 (-2700 2200)(-2100 2200);
FORCEPROP 2 LAST SIG_NAME TP_PCH_RSVD12
J 0
(-2465 2210);
DISPLAY 0.617021 (-2465 2210);
PAINT ORANGE (-2465 2210);
FORCEPROP 2 LASTPROP $XRERR UNIQUE?
J 0
(-2070 2200);
DISPLAY 0.638298 (-2070 2200);
PAINT MONO (-2070 2200);
DISPLAY INVISIBLE (-2070 2200);
WIRE 16 -1 (-2700 2750)(-2100 2750);
FORCEPROP 2 LAST SIG_NAME TP_PCH_HDA_SDI_0
J 0
(-2465 2760);
DISPLAY 0.617021 (-2465 2760);
PAINT ORANGE (-2465 2760);
FORCEPROP 2 LASTPROP $XRERR UNIQUE?
J 0
(-2070 2750);
DISPLAY 0.638298 (-2070 2750);
PAINT MONO (-2070 2750);
DISPLAY INVISIBLE (-2070 2750);
WIRE 16 -1 (-2700 3600)(-2100 3600);
FORCEPROP 0 LAST SIG_NAME TP_SPI_PCH_CS1_R1_N
J 0
(-2465 3610);
DISPLAY 0.617021 (-2465 3610);
PAINT ORANGE (-2465 3610);
FORCEPROP 2 LASTPROP $XRERR UNIQUE?
J 0
(-2070 3600);
DISPLAY 0.638298 (-2070 3600);
PAINT MONO (-2070 3600);
DISPLAY INVISIBLE (-2070 3600);
WIRE 16 -1 (-2700 3850)(-2100 3850);
FORCEPROP 2 LAST SIG_NAME TP_PCH_RSVD26
J 0
(-2465 3860);
DISPLAY 0.617021 (-2465 3860);
PAINT ORANGE (-2465 3860);
FORCEPROP 2 LASTPROP $XRERR UNIQUE?
J 0
(-2070 3850);
DISPLAY 0.638298 (-2070 3850);
PAINT MONO (-2070 3850);
DISPLAY INVISIBLE (-2070 3850);
WIRE 16 -1 (-2700 3900)(-2100 3900);
FORCEPROP 2 LAST SIG_NAME TP_PCH_RSVD27
J 0
(-2465 3910);
DISPLAY 0.617021 (-2465 3910);
PAINT ORANGE (-2465 3910);
FORCEPROP 2 LASTPROP $XRERR UNIQUE?
J 0
(-2070 3900);
DISPLAY 0.638298 (-2070 3900);
PAINT MONO (-2070 3900);
DISPLAY INVISIBLE (-2070 3900);
WIRE 16 -1 (-2700 3750)(-2100 3750);
FORCEPROP 2 LAST SIG_NAME TP_PCH_RSVD46
J 0
(-2465 3760);
DISPLAY 0.617021 (-2465 3760);
PAINT ORANGE (-2465 3760);
FORCEPROP 2 LASTPROP $XRERR UNIQUE?
J 0
(-2070 3750);
DISPLAY 0.638298 (-2070 3750);
PAINT MONO (-2070 3750);
DISPLAY INVISIBLE (-2070 3750);
WIRE 16 -1 (-2700 2100)(-1425 2100);
FORCEPROP 2 LAST SIG_NAME FM_WBG_PRSNT_N
J 2
(-1435 2110);
DISPLAY 0.617021 (-1435 2110);
PAINT ORANGE (-1435 2110);
WIRE 16 -1 (-1425 3150)(-1825 3150);
FORCEPROP 2 LAST SIG_NAME SPI_PCH_MOSI
J 2
(-1425 3160);
DISPLAY 0.617021 (-1425 3160);
PAINT ORANGE (-1425 3160);
WIRE 16 -1 (-1425 3550)(-1850 3550);
FORCEPROP 2 LAST SIG_NAME SPI_PCH_CS0_N
J 2
(-1425 3560);
DISPLAY 0.617021 (-1425 3560);
PAINT ORANGE (-1425 3560);
DOT 1 (-7200 2750);
DOT 1 (-3050 675);
DOT 1 (-3050 775);
DOT 1 (-3050 875);
DOT 1 (-3050 975);
DOT 1 (-2325 575);
DOT 1 (-3050 1075);
DOT 1 (-2325 1175);
DOT 1 (-1850 575);
DOT 1 (-1350 575);
DOT 1 (-1850 1175);
DOT 1 (-1350 1175);
DOT 1 (-675 675);
DOT 1 (-675 775);
DOT 1 (-675 875);
DOT 1 (-675 975);
DOT 1 (-675 1075);
FORCENOTE
SINT_PRSNT
(-2300 1000) 0;
DISPLAY LEFT (-2300 1000);
DISPLAY 1.021277 (-2300 1000);
PAINT PURPLE (-2300 1000);
FORCENOTE
TP FAB1 RENAME 0307
(-7750 2400) 0;
DISPLAY LEFT (-7750 2400);
DISPLAY 0.638298 (-7750 2400);
PAINT RED (-7750 2400);
FORCENOTE
TP FAB1 RENAME 1218
(-7550 2800) 0;
DISPLAY LEFT (-7550 2800);
DISPLAY 1.021277 (-7550 2800);
PAINT RED (-7550 2800);
FORCENOTE
0
(-2100 900) 0;
DISPLAY LEFT (-2100 900);
DISPLAY 1.021277 (-2100 900);
PAINT PURPLE (-2100 900);
FORCENOTE
INSTALLED WRONG DIRECTION
(-1300 600) 0;
DISPLAY LEFT (-1300 600);
DISPLAY 0.638298 (-1300 600);
PAINT PURPLE (-1300 600);
FORCENOTE
X
(-1625 600) 0;
DISPLAY LEFT (-1625 600);
DISPLAY 1.021277 (-1625 600);
PAINT PURPLE (-1625 600);
FORCENOTE
1
(-1625 700) 0;
DISPLAY LEFT (-1625 700);
DISPLAY 1.021277 (-1625 700);
PAINT PURPLE (-1625 700);
FORCENOTE
COMMENT
(-1225 1100) 0;
DISPLAY LEFT (-1225 1100);
DISPLAY 1.021277 (-1225 1100);
PAINT PURPLE (-1225 1100);
FORCENOTE
LBG
(-1125 700) 0;
DISPLAY LEFT (-1125 700);
DISPLAY 0.808511 (-1125 700);
PAINT PURPLE (-1125 700);
FORCENOTE
RSVD
(-1125 900) 0;
DISPLAY LEFT (-1125 900);
DISPLAY 0.808511 (-1125 900);
PAINT PURPLE (-1125 900);
FORCENOTE
WBG
(-1125 800) 0;
DISPLAY LEFT (-1125 800);
DISPLAY 0.808511 (-1125 800);
PAINT PURPLE (-1125 800);
FORCENOTE
PIN D8
(-1725 1100) 0;
DISPLAY LEFT (-1725 1100);
DISPLAY 1.021277 (-1725 1100);
PAINT PURPLE (-1725 1100);
FORCENOTE
WBG_PRSNT
(-1775 1000) 0;
DISPLAY LEFT (-1775 1000);
DISPLAY 1.021277 (-1775 1000);
PAINT PURPLE (-1775 1000);
FORCENOTE
1
(-1625 900) 0;
DISPLAY LEFT (-1625 900);
DISPLAY 1.021277 (-1625 900);
PAINT PURPLE (-1625 900);
FORCENOTE
0
(-1625 800) 0;
DISPLAY LEFT (-1625 800);
DISPLAY 1.021277 (-1625 800);
PAINT PURPLE (-1625 800);
FORCENOTE
PIN C18
(-2200 1100) 0;
DISPLAY LEFT (-2200 1100);
DISPLAY 1.021277 (-2200 1100);
PAINT PURPLE (-2200 1100);
FORCENOTE
PCH DETECTION
(-3025 1200) 0;
DISPLAY LEFT (-3025 1200);
DISPLAY 1.276596 (-3025 1200);
PAINT PURPLE (-3025 1200);
FORCENOTE
CGC_DUT_DETECT#
(-3000 1100) 0;
DISPLAY LEFT (-3000 1100);
DISPLAY 1.021277 (-3000 1100);
PAINT PURPLE (-3000 1100);
FORCENOTE
X
(-2100 600) 0;
DISPLAY LEFT (-2100 600);
DISPLAY 1.021277 (-2100 600);
PAINT PURPLE (-2100 600);
FORCENOTE
1
(-2100 800) 0;
DISPLAY LEFT (-2100 800);
DISPLAY 1.021277 (-2100 800);
PAINT PURPLE (-2100 800);
FORCENOTE
1
(-2100 700) 0;
DISPLAY LEFT (-2100 700);
DISPLAY 1.021277 (-2100 700);
PAINT PURPLE (-2100 700);
FORCENOTE
1
(-2725 600) 0;
DISPLAY LEFT (-2725 600);
DISPLAY 1.021277 (-2725 600);
PAINT PURPLE (-2725 600);
FORCENOTE
0
(-2725 800) 0;
DISPLAY LEFT (-2725 800);
DISPLAY 1.021277 (-2725 800);
PAINT PURPLE (-2725 800);
FORCENOTE
0
(-2725 900) 0;
DISPLAY LEFT (-2725 900);
DISPLAY 1.021277 (-2725 900);
PAINT PURPLE (-2725 900);
FORCENOTE
0
(-2725 700) 0;
DISPLAY LEFT (-2725 700);
DISPLAY 1.021277 (-2725 700);
PAINT PURPLE (-2725 700);
FORCENOTE
ROOM=SB
(-8200 375) 0;
DISPLAY LEFT (-8200 375);
DISPLAY 1.021277 (-8200 375);
PAINT PURPLE (-8200 375);
QUIT
